FILE_TYPE = MACRO_DRAWING;
SET COLOR_WIRE YELLOW;
SET COLOR_PROP ORANGE;
SET COLOR_DOT WHITE;
SET COLOR_ARC YELLOW;
SET COLOR_BODY GREEN;
SET COLOR_NOTE PURPLE;
SET PROP_DISPLAY VALUE;
SET PAGE_NUMBER P48;
FORCEADD GENOA_SP5..35
(-4550 3550);
FORCEPROP 1 LAST LOCATION U26
J 0
(-5195 6381);
DISPLAY 0.489362 (-5195 6381);
PAINT SKYBLUE (-5195 6381);
FORCEPROP 0 LAST $SEC 35
J 0
(-5175 6425);
DISPLAY 0.680851 (-5175 6425);
PAINT MONO (-5175 6425);
DISPLAY INVISIBLE (-5175 6425);
FORCEPROP 0 LAST CDS_SEC 35
J 0
(-5200 6375);
DISPLAY 1.021277 (-5200 6375);
DISPLAY INVISIBLE (-5200 6375);
FORCEPROP 0 LASTPIN (-5350 2925) $PN BC9
J 2
(-5360 2935);
DISPLAY 0.489362 (-5360 2935);
PAINT MONO (-5360 2935);
FORCEPROP 0 LASTPIN (-5350 2875) $PN BD9
J 2
(-5360 2885);
DISPLAY 0.489362 (-5360 2885);
PAINT MONO (-5360 2885);
FORCEPROP 0 LASTPIN (-5350 1775) $PN BF9
J 2
(-5360 1785);
DISPLAY 0.489362 (-5360 1785);
PAINT MONO (-5360 1785);
FORCEPROP 0 LASTPIN (-5350 1725) $PN BG9
J 2
(-5360 1735);
DISPLAY 0.489362 (-5360 1735);
PAINT MONO (-5360 1735);
FORCEPROP 0 LASTPIN (-5350 2075) $PN AT11
J 2
(-5360 2085);
DISPLAY 0.489362 (-5360 2085);
PAINT MONO (-5360 2085);
FORCEPROP 0 LASTPIN (-5350 1975) $PN AU10
J 2
(-5360 1985);
DISPLAY 0.489362 (-5360 1985);
PAINT MONO (-5360 1985);
FORCEPROP 0 LASTPIN (-5350 2775) $PN AU9
J 2
(-5360 2785);
DISPLAY 0.489362 (-5360 2785);
PAINT MONO (-5360 2785);
FORCEPROP 0 LASTPIN (-5350 2725) $PN AV11
J 2
(-5360 2735);
DISPLAY 0.489362 (-5360 2735);
PAINT MONO (-5360 2735);
FORCEPROP 0 LASTPIN (-5350 2625) $PN BN10
J 2
(-5360 2635);
DISPLAY 0.489362 (-5360 2635);
PAINT MONO (-5360 2635);
FORCEPROP 0 LASTPIN (-5350 1625) $PN AV9
J 2
(-5360 1635);
DISPLAY 0.489362 (-5360 1635);
PAINT MONO (-5360 1635);
FORCEPROP 0 LASTPIN (-5350 1575) $PN AW10
J 2
(-5360 1585);
DISPLAY 0.489362 (-5360 1585);
PAINT MONO (-5360 1585);
FORCEPROP 0 LASTPIN (-5350 1475) $PN BP11
J 2
(-5360 1485);
DISPLAY 0.489362 (-5360 1485);
PAINT MONO (-5360 1485);
FORCEPROP 0 LASTPIN (-5350 3775) $PN AW9
J 2
(-5360 3785);
DISPLAY 0.489362 (-5360 3785);
PAINT MONO (-5360 3785);
FORCEPROP 0 LASTPIN (-5350 3725) $PN AY9
J 2
(-5360 3735);
DISPLAY 0.489362 (-5360 3735);
PAINT MONO (-5360 3735);
FORCEPROP 0 LASTPIN (-5350 3675) $PN AY11
J 2
(-5360 3685);
DISPLAY 0.489362 (-5360 3685);
PAINT MONO (-5360 3685);
FORCEPROP 0 LASTPIN (-5350 3625) $PN BA10
J 2
(-5360 3635);
DISPLAY 0.489362 (-5360 3635);
PAINT MONO (-5360 3635);
FORCEPROP 0 LASTPIN (-5350 3575) $PN BA9
J 2
(-5360 3585);
DISPLAY 0.489362 (-5360 3585);
PAINT MONO (-5360 3585);
FORCEPROP 0 LASTPIN (-5350 3525) $PN BB9
J 2
(-5360 3535);
DISPLAY 0.489362 (-5360 3535);
PAINT MONO (-5360 3535);
FORCEPROP 0 LASTPIN (-5350 3475) $PN BB11
J 2
(-5360 3485);
DISPLAY 0.489362 (-5360 3485);
PAINT MONO (-5360 3485);
FORCEPROP 0 LASTPIN (-3750 2325) $PN AJ9
J 0
(-3740 2335);
DISPLAY 0.489362 (-3740 2335);
PAINT MONO (-3740 2335);
FORCEPROP 0 LASTPIN (-3750 2275) $PN AK11
J 0
(-3740 2285);
DISPLAY 0.489362 (-3740 2285);
PAINT MONO (-3740 2285);
FORCEPROP 0 LASTPIN (-3750 2225) $PN AK9
J 0
(-3740 2235);
DISPLAY 0.489362 (-3740 2235);
PAINT MONO (-3740 2235);
FORCEPROP 0 LASTPIN (-3750 2175) $PN AL10
J 0
(-3740 2185);
DISPLAY 0.489362 (-3740 2185);
PAINT MONO (-3740 2185);
FORCEPROP 0 LASTPIN (-3750 2125) $PN AN9
J 0
(-3740 2135);
DISPLAY 0.489362 (-3740 2135);
PAINT MONO (-3740 2135);
FORCEPROP 0 LASTPIN (-3750 2075) $PN AP11
J 0
(-3740 2085);
DISPLAY 0.489362 (-3740 2085);
PAINT MONO (-3740 2085);
FORCEPROP 0 LASTPIN (-3750 2025) $PN AP9
J 0
(-3740 2035);
DISPLAY 0.489362 (-3740 2035);
PAINT MONO (-3740 2035);
FORCEPROP 0 LASTPIN (-3750 1975) $PN AR10
J 0
(-3740 1985);
DISPLAY 0.489362 (-3740 1985);
PAINT MONO (-3740 1985);
FORCEPROP 0 LASTPIN (-3750 5925) $PN E9
J 0
(-3740 5935);
DISPLAY 0.489362 (-3740 5935);
PAINT MONO (-3740 5935);
FORCEPROP 0 LASTPIN (-3750 5875) $PN F11
J 0
(-3740 5885);
DISPLAY 0.489362 (-3740 5885);
PAINT MONO (-3740 5885);
FORCEPROP 0 LASTPIN (-3750 5825) $PN F9
J 0
(-3740 5835);
DISPLAY 0.489362 (-3740 5835);
PAINT MONO (-3740 5835);
FORCEPROP 0 LASTPIN (-3750 5775) $PN G10
J 0
(-3740 5785);
DISPLAY 0.489362 (-3740 5785);
PAINT MONO (-3740 5785);
FORCEPROP 0 LASTPIN (-3750 5725) $PN J9
J 0
(-3740 5735);
DISPLAY 0.489362 (-3740 5735);
PAINT MONO (-3740 5735);
FORCEPROP 0 LASTPIN (-3750 5675) $PN K11
J 0
(-3740 5685);
DISPLAY 0.489362 (-3740 5685);
PAINT MONO (-3740 5685);
FORCEPROP 0 LASTPIN (-3750 5625) $PN K9
J 0
(-3740 5635);
DISPLAY 0.489362 (-3740 5635);
PAINT MONO (-3740 5635);
FORCEPROP 0 LASTPIN (-3750 5575) $PN L10
J 0
(-3740 5585);
DISPLAY 0.489362 (-3740 5585);
PAINT MONO (-3740 5585);
FORCEPROP 0 LASTPIN (-3750 5475) $PN L9
J 0
(-3740 5485);
DISPLAY 0.489362 (-3740 5485);
PAINT MONO (-3740 5485);
FORCEPROP 0 LASTPIN (-3750 5425) $PN M11
J 0
(-3740 5435);
DISPLAY 0.489362 (-3740 5435);
PAINT MONO (-3740 5435);
FORCEPROP 0 LASTPIN (-3750 5375) $PN M9
J 0
(-3740 5385);
DISPLAY 0.489362 (-3740 5385);
PAINT MONO (-3740 5385);
FORCEPROP 0 LASTPIN (-3750 5325) $PN N10
J 0
(-3740 5335);
DISPLAY 0.489362 (-3740 5335);
PAINT MONO (-3740 5335);
FORCEPROP 0 LASTPIN (-3750 5275) $PN R9
J 0
(-3740 5285);
DISPLAY 0.489362 (-3740 5285);
PAINT MONO (-3740 5285);
FORCEPROP 0 LASTPIN (-3750 5225) $PN T11
J 0
(-3740 5235);
DISPLAY 0.489362 (-3740 5235);
PAINT MONO (-3740 5235);
FORCEPROP 0 LASTPIN (-3750 5175) $PN T9
J 0
(-3740 5185);
DISPLAY 0.489362 (-3740 5185);
PAINT MONO (-3740 5185);
FORCEPROP 0 LASTPIN (-3750 5125) $PN U10
J 0
(-3740 5135);
DISPLAY 0.489362 (-3740 5135);
PAINT MONO (-3740 5135);
FORCEPROP 0 LASTPIN (-3750 5025) $PN U9
J 0
(-3740 5035);
DISPLAY 0.489362 (-3740 5035);
PAINT MONO (-3740 5035);
FORCEPROP 0 LASTPIN (-3750 4975) $PN V11
J 0
(-3740 4985);
DISPLAY 0.489362 (-3740 4985);
PAINT MONO (-3740 4985);
FORCEPROP 0 LASTPIN (-3750 4925) $PN V9
J 0
(-3740 4935);
DISPLAY 0.489362 (-3740 4935);
PAINT MONO (-3740 4935);
FORCEPROP 0 LASTPIN (-3750 4875) $PN W10
J 0
(-3740 4885);
DISPLAY 0.489362 (-3740 4885);
PAINT MONO (-3740 4885);
FORCEPROP 0 LASTPIN (-3750 4825) $PN AA9
J 0
(-3740 4835);
DISPLAY 0.489362 (-3740 4835);
PAINT MONO (-3740 4835);
FORCEPROP 0 LASTPIN (-3750 4775) $PN AB11
J 0
(-3740 4785);
DISPLAY 0.489362 (-3740 4785);
PAINT MONO (-3740 4785);
FORCEPROP 0 LASTPIN (-3750 4725) $PN AB9
J 0
(-3740 4735);
DISPLAY 0.489362 (-3740 4735);
PAINT MONO (-3740 4735);
FORCEPROP 0 LASTPIN (-3750 4675) $PN AC10
J 0
(-3740 4685);
DISPLAY 0.489362 (-3740 4685);
PAINT MONO (-3740 4685);
FORCEPROP 0 LASTPIN (-3750 4575) $PN AC9
J 0
(-3740 4585);
DISPLAY 0.489362 (-3740 4585);
PAINT MONO (-3740 4585);
FORCEPROP 0 LASTPIN (-3750 4525) $PN AD11
J 0
(-3740 4535);
DISPLAY 0.489362 (-3740 4535);
PAINT MONO (-3740 4535);
FORCEPROP 0 LASTPIN (-3750 4475) $PN AD9
J 0
(-3740 4485);
DISPLAY 0.489362 (-3740 4485);
PAINT MONO (-3740 4485);
FORCEPROP 0 LASTPIN (-3750 4425) $PN AE10
J 0
(-3740 4435);
DISPLAY 0.489362 (-3740 4435);
PAINT MONO (-3740 4435);
FORCEPROP 0 LASTPIN (-3750 4375) $PN AG9
J 0
(-3740 4385);
DISPLAY 0.489362 (-3740 4385);
PAINT MONO (-3740 4385);
FORCEPROP 0 LASTPIN (-3750 4325) $PN AH11
J 0
(-3740 4335);
DISPLAY 0.489362 (-3740 4335);
PAINT MONO (-3740 4335);
FORCEPROP 0 LASTPIN (-3750 4275) $PN AH9
J 0
(-3740 4285);
DISPLAY 0.489362 (-3740 4285);
PAINT MONO (-3740 4285);
FORCEPROP 0 LASTPIN (-3750 4225) $PN AJ10
J 0
(-3740 4235);
DISPLAY 0.489362 (-3740 4235);
PAINT MONO (-3740 4235);
FORCEPROP 0 LASTPIN (-5350 5925) $PN G9
J 2
(-5360 5935);
DISPLAY 0.489362 (-5360 5935);
PAINT MONO (-5360 5935);
FORCEPROP 0 LASTPIN (-5350 5825) $PN N9
J 2
(-5360 5835);
DISPLAY 0.489362 (-5360 5835);
PAINT MONO (-5360 5835);
FORCEPROP 0 LASTPIN (-5350 5725) $PN W9
J 2
(-5360 5735);
DISPLAY 0.489362 (-5360 5735);
PAINT MONO (-5360 5735);
FORCEPROP 0 LASTPIN (-5350 5625) $PN AE9
J 2
(-5360 5635);
DISPLAY 0.489362 (-5360 5635);
PAINT MONO (-5360 5635);
FORCEPROP 0 LASTPIN (-5350 5525) $PN AL9
J 2
(-5360 5535);
DISPLAY 0.489362 (-5360 5535);
PAINT MONO (-5360 5535);
FORCEPROP 0 LASTPIN (-5350 5425) $PN J10
J 2
(-5360 5435);
DISPLAY 0.489362 (-5360 5435);
PAINT MONO (-5360 5435);
FORCEPROP 0 LASTPIN (-5350 5325) $PN R10
J 2
(-5360 5335);
DISPLAY 0.489362 (-5360 5335);
PAINT MONO (-5360 5335);
FORCEPROP 0 LASTPIN (-5350 5225) $PN AA10
J 2
(-5360 5235);
DISPLAY 0.489362 (-5360 5235);
PAINT MONO (-5360 5235);
FORCEPROP 0 LASTPIN (-5350 5125) $PN AG10
J 2
(-5360 5135);
DISPLAY 0.489362 (-5360 5135);
PAINT MONO (-5360 5135);
FORCEPROP 0 LASTPIN (-5350 5025) $PN AN10
J 2
(-5360 5035);
DISPLAY 0.489362 (-5360 5035);
PAINT MONO (-5360 5035);
FORCEPROP 0 LASTPIN (-5350 5875) $PN H9
J 2
(-5360 5885);
DISPLAY 0.489362 (-5360 5885);
PAINT MONO (-5360 5885);
FORCEPROP 0 LASTPIN (-5350 5775) $PN P9
J 2
(-5360 5785);
DISPLAY 0.489362 (-5360 5785);
PAINT MONO (-5360 5785);
FORCEPROP 0 LASTPIN (-5350 5675) $PN Y9
J 2
(-5360 5685);
DISPLAY 0.489362 (-5360 5685);
PAINT MONO (-5360 5685);
FORCEPROP 0 LASTPIN (-5350 5575) $PN AF9
J 2
(-5360 5585);
DISPLAY 0.489362 (-5360 5585);
PAINT MONO (-5360 5585);
FORCEPROP 0 LASTPIN (-5350 5475) $PN AM9
J 2
(-5360 5485);
DISPLAY 0.489362 (-5360 5485);
PAINT MONO (-5360 5485);
FORCEPROP 0 LASTPIN (-5350 5375) $PN H11
J 2
(-5360 5385);
DISPLAY 0.489362 (-5360 5385);
PAINT MONO (-5360 5385);
FORCEPROP 0 LASTPIN (-5350 5275) $PN P11
J 2
(-5360 5285);
DISPLAY 0.489362 (-5360 5285);
PAINT MONO (-5360 5285);
FORCEPROP 0 LASTPIN (-5350 5175) $PN Y11
J 2
(-5360 5185);
DISPLAY 0.489362 (-5360 5185);
PAINT MONO (-5360 5185);
FORCEPROP 0 LASTPIN (-5350 5075) $PN AF11
J 2
(-5360 5085);
DISPLAY 0.489362 (-5360 5085);
PAINT MONO (-5360 5085);
FORCEPROP 0 LASTPIN (-5350 4975) $PN AM11
J 2
(-5360 4985);
DISPLAY 0.489362 (-5360 4985);
PAINT MONO (-5360 4985);
FORCEPROP 0 LASTPIN (-5350 2525) $PN BC10
J 2
(-5360 2535);
DISPLAY 0.489362 (-5360 2535);
PAINT MONO (-5360 2535);
FORCEPROP 0 LASTPIN (-5350 2425) $PN BM11
J 2
(-5360 2435);
DISPLAY 0.489362 (-5360 2435);
PAINT MONO (-5360 2435);
FORCEPROP 0 LASTPIN (-5350 2375) $PN BN9
J 2
(-5360 2385);
DISPLAY 0.489362 (-5360 2385);
PAINT MONO (-5360 2385);
FORCEPROP 0 LASTPIN (-5350 2275) $PN BP9
J 2
(-5360 2285);
DISPLAY 0.489362 (-5360 2285);
PAINT MONO (-5360 2285);
FORCEPROP 0 LASTPIN (-5350 1375) $PN BL9
J 2
(-5360 1385);
DISPLAY 0.489362 (-5360 1385);
PAINT MONO (-5360 1385);
FORCEPROP 0 LASTPIN (-5350 1325) $PN BM9
J 2
(-5360 1335);
DISPLAY 0.489362 (-5360 1335);
PAINT MONO (-5360 1335);
FORCEPROP 0 LASTPIN (-5350 1225) $PN BR9
J 2
(-5360 1235);
DISPLAY 0.489362 (-5360 1235);
PAINT MONO (-5360 1235);
FORCEPROP 0 LASTPIN (-5350 3375) $PN BG10
J 2
(-5360 3385);
DISPLAY 0.489362 (-5360 3385);
PAINT MONO (-5360 3385);
FORCEPROP 0 LASTPIN (-5350 3325) $PN BH11
J 2
(-5360 3335);
DISPLAY 0.489362 (-5360 3335);
PAINT MONO (-5360 3335);
FORCEPROP 0 LASTPIN (-5350 3275) $PN BH9
J 2
(-5360 3285);
DISPLAY 0.489362 (-5360 3285);
PAINT MONO (-5360 3285);
FORCEPROP 0 LASTPIN (-5350 3225) $PN BJ9
J 2
(-5360 3235);
DISPLAY 0.489362 (-5360 3235);
PAINT MONO (-5360 3235);
FORCEPROP 0 LASTPIN (-5350 3175) $PN BJ10
J 2
(-5360 3185);
DISPLAY 0.489362 (-5360 3185);
PAINT MONO (-5360 3185);
FORCEPROP 0 LASTPIN (-5350 3125) $PN BK11
J 2
(-5360 3135);
DISPLAY 0.489362 (-5360 3135);
PAINT MONO (-5360 3135);
FORCEPROP 0 LASTPIN (-5350 3075) $PN BK9
J 2
(-5360 3085);
DISPLAY 0.489362 (-5360 3085);
PAINT MONO (-5360 3085);
FORCEPROP 0 LASTPIN (-3750 1875) $PN BY9
J 0
(-3740 1885);
DISPLAY 0.489362 (-3740 1885);
PAINT MONO (-3740 1885);
FORCEPROP 0 LASTPIN (-3750 1825) $PN CA10
J 0
(-3740 1835);
DISPLAY 0.489362 (-3740 1835);
PAINT MONO (-3740 1835);
FORCEPROP 0 LASTPIN (-3750 1775) $PN CA9
J 0
(-3740 1785);
DISPLAY 0.489362 (-3740 1785);
PAINT MONO (-3740 1785);
FORCEPROP 0 LASTPIN (-3750 1725) $PN CB11
J 0
(-3740 1735);
DISPLAY 0.489362 (-3740 1735);
PAINT MONO (-3740 1735);
FORCEPROP 0 LASTPIN (-3750 1675) $PN BT9
J 0
(-3740 1685);
DISPLAY 0.489362 (-3740 1685);
PAINT MONO (-3740 1685);
FORCEPROP 0 LASTPIN (-3750 1625) $PN BU10
J 0
(-3740 1635);
DISPLAY 0.489362 (-3740 1635);
PAINT MONO (-3740 1635);
FORCEPROP 0 LASTPIN (-3750 1575) $PN BU9
J 0
(-3740 1585);
DISPLAY 0.489362 (-3740 1585);
PAINT MONO (-3740 1585);
FORCEPROP 0 LASTPIN (-3750 1525) $PN BV11
J 0
(-3740 1535);
DISPLAY 0.489362 (-3740 1535);
PAINT MONO (-3740 1535);
FORCEPROP 0 LASTPIN (-3750 4125) $PN CB9
J 0
(-3740 4135);
DISPLAY 0.489362 (-3740 4135);
PAINT MONO (-3740 4135);
FORCEPROP 0 LASTPIN (-3750 4075) $PN CC10
J 0
(-3740 4085);
DISPLAY 0.489362 (-3740 4085);
PAINT MONO (-3740 4085);
FORCEPROP 0 LASTPIN (-3750 4025) $PN CC9
J 0
(-3740 4035);
DISPLAY 0.489362 (-3740 4035);
PAINT MONO (-3740 4035);
FORCEPROP 0 LASTPIN (-3750 3975) $PN CD11
J 0
(-3740 3985);
DISPLAY 0.489362 (-3740 3985);
PAINT MONO (-3740 3985);
FORCEPROP 0 LASTPIN (-3750 3925) $PN CF9
J 0
(-3740 3935);
DISPLAY 0.489362 (-3740 3935);
PAINT MONO (-3740 3935);
FORCEPROP 0 LASTPIN (-3750 3875) $PN CG10
J 0
(-3740 3885);
DISPLAY 0.489362 (-3740 3885);
PAINT MONO (-3740 3885);
FORCEPROP 0 LASTPIN (-3750 3825) $PN CG9
J 0
(-3740 3835);
DISPLAY 0.489362 (-3740 3835);
PAINT MONO (-3740 3835);
FORCEPROP 0 LASTPIN (-3750 3775) $PN CH11
J 0
(-3740 3785);
DISPLAY 0.489362 (-3740 3785);
PAINT MONO (-3740 3785);
FORCEPROP 0 LASTPIN (-3750 3675) $PN CH9
J 0
(-3740 3685);
DISPLAY 0.489362 (-3740 3685);
PAINT MONO (-3740 3685);
FORCEPROP 0 LASTPIN (-3750 3625) $PN CJ10
J 0
(-3740 3635);
DISPLAY 0.489362 (-3740 3635);
PAINT MONO (-3740 3635);
FORCEPROP 0 LASTPIN (-3750 3575) $PN CJ9
J 0
(-3740 3585);
DISPLAY 0.489362 (-3740 3585);
PAINT MONO (-3740 3585);
FORCEPROP 0 LASTPIN (-3750 3525) $PN CK11
J 0
(-3740 3535);
DISPLAY 0.489362 (-3740 3535);
PAINT MONO (-3740 3535);
FORCEPROP 0 LASTPIN (-3750 3475) $PN CM9
J 0
(-3740 3485);
DISPLAY 0.489362 (-3740 3485);
PAINT MONO (-3740 3485);
FORCEPROP 0 LASTPIN (-3750 3425) $PN CN10
J 0
(-3740 3435);
DISPLAY 0.489362 (-3740 3435);
PAINT MONO (-3740 3435);
FORCEPROP 0 LASTPIN (-3750 3375) $PN CN9
J 0
(-3740 3385);
DISPLAY 0.489362 (-3740 3385);
PAINT MONO (-3740 3385);
FORCEPROP 0 LASTPIN (-3750 3325) $PN CP11
J 0
(-3740 3335);
DISPLAY 0.489362 (-3740 3335);
PAINT MONO (-3740 3335);
FORCEPROP 0 LASTPIN (-3750 3225) $PN CP9
J 0
(-3740 3235);
DISPLAY 0.489362 (-3740 3235);
PAINT MONO (-3740 3235);
FORCEPROP 0 LASTPIN (-3750 3175) $PN CR10
J 0
(-3740 3185);
DISPLAY 0.489362 (-3740 3185);
PAINT MONO (-3740 3185);
FORCEPROP 0 LASTPIN (-3750 3125) $PN CR9
J 0
(-3740 3135);
DISPLAY 0.489362 (-3740 3135);
PAINT MONO (-3740 3135);
FORCEPROP 0 LASTPIN (-3750 3075) $PN CT11
J 0
(-3740 3085);
DISPLAY 0.489362 (-3740 3085);
PAINT MONO (-3740 3085);
FORCEPROP 0 LASTPIN (-3750 3025) $PN CV9
J 0
(-3740 3035);
DISPLAY 0.489362 (-3740 3035);
PAINT MONO (-3740 3035);
FORCEPROP 0 LASTPIN (-3750 2975) $PN CW10
J 0
(-3740 2985);
DISPLAY 0.489362 (-3740 2985);
PAINT MONO (-3740 2985);
FORCEPROP 0 LASTPIN (-3750 2925) $PN CW9
J 0
(-3740 2935);
DISPLAY 0.489362 (-3740 2935);
PAINT MONO (-3740 2935);
FORCEPROP 0 LASTPIN (-3750 2875) $PN CY11
J 0
(-3740 2885);
DISPLAY 0.489362 (-3740 2885);
PAINT MONO (-3740 2885);
FORCEPROP 0 LASTPIN (-3750 2775) $PN CY9
J 0
(-3740 2785);
DISPLAY 0.489362 (-3740 2785);
PAINT MONO (-3740 2785);
FORCEPROP 0 LASTPIN (-3750 2725) $PN DA10
J 0
(-3740 2735);
DISPLAY 0.489362 (-3740 2735);
PAINT MONO (-3740 2735);
FORCEPROP 0 LASTPIN (-3750 2675) $PN DA9
J 0
(-3740 2685);
DISPLAY 0.489362 (-3740 2685);
PAINT MONO (-3740 2685);
FORCEPROP 0 LASTPIN (-3750 2625) $PN DB11
J 0
(-3740 2635);
DISPLAY 0.489362 (-3740 2635);
PAINT MONO (-3740 2635);
FORCEPROP 0 LASTPIN (-3750 2575) $PN DD9
J 0
(-3740 2585);
DISPLAY 0.489362 (-3740 2585);
PAINT MONO (-3740 2585);
FORCEPROP 0 LASTPIN (-3750 2525) $PN DE10
J 0
(-3740 2535);
DISPLAY 0.489362 (-3740 2535);
PAINT MONO (-3740 2535);
FORCEPROP 0 LASTPIN (-3750 2475) $PN DE9
J 0
(-3740 2485);
DISPLAY 0.489362 (-3740 2485);
PAINT MONO (-3740 2485);
FORCEPROP 0 LASTPIN (-3750 2425) $PN DF9
J 0
(-3740 2435);
DISPLAY 0.489362 (-3740 2435);
PAINT MONO (-3740 2435);
FORCEPROP 0 LASTPIN (-5350 4875) $PN CD9
J 2
(-5360 4885);
DISPLAY 0.489362 (-5360 4885);
PAINT MONO (-5360 4885);
FORCEPROP 0 LASTPIN (-5350 4775) $PN CK9
J 2
(-5360 4785);
DISPLAY 0.489362 (-5360 4785);
PAINT MONO (-5360 4785);
FORCEPROP 0 LASTPIN (-5350 4675) $PN CT9
J 2
(-5360 4685);
DISPLAY 0.489362 (-5360 4685);
PAINT MONO (-5360 4685);
FORCEPROP 0 LASTPIN (-5350 4575) $PN DB9
J 2
(-5360 4585);
DISPLAY 0.489362 (-5360 4585);
PAINT MONO (-5360 4585);
FORCEPROP 0 LASTPIN (-5350 4475) $PN BY11
J 2
(-5360 4485);
DISPLAY 0.489362 (-5360 4485);
PAINT MONO (-5360 4485);
FORCEPROP 0 LASTPIN (-5350 4375) $PN CF11
J 2
(-5360 4385);
DISPLAY 0.489362 (-5360 4385);
PAINT MONO (-5360 4385);
FORCEPROP 0 LASTPIN (-5350 4275) $PN CM11
J 2
(-5360 4285);
DISPLAY 0.489362 (-5360 4285);
PAINT MONO (-5360 4285);
FORCEPROP 0 LASTPIN (-5350 4175) $PN CV11
J 2
(-5360 4185);
DISPLAY 0.489362 (-5360 4185);
PAINT MONO (-5360 4185);
FORCEPROP 0 LASTPIN (-5350 4075) $PN DD11
J 2
(-5360 4085);
DISPLAY 0.489362 (-5360 4085);
PAINT MONO (-5360 4085);
FORCEPROP 0 LASTPIN (-5350 3975) $PN BV9
J 2
(-5360 3985);
DISPLAY 0.489362 (-5360 3985);
PAINT MONO (-5360 3985);
FORCEPROP 0 LASTPIN (-5350 4825) $PN CE9
J 2
(-5360 4835);
DISPLAY 0.489362 (-5360 4835);
PAINT MONO (-5360 4835);
FORCEPROP 0 LASTPIN (-5350 4725) $PN CL9
J 2
(-5360 4735);
DISPLAY 0.489362 (-5360 4735);
PAINT MONO (-5360 4735);
FORCEPROP 0 LASTPIN (-5350 4625) $PN CU9
J 2
(-5360 4635);
DISPLAY 0.489362 (-5360 4635);
PAINT MONO (-5360 4635);
FORCEPROP 0 LASTPIN (-5350 4525) $PN DC9
J 2
(-5360 4535);
DISPLAY 0.489362 (-5360 4535);
PAINT MONO (-5360 4535);
FORCEPROP 0 LASTPIN (-5350 4425) $PN BW10
J 2
(-5360 4435);
DISPLAY 0.489362 (-5360 4435);
PAINT MONO (-5360 4435);
FORCEPROP 0 LASTPIN (-5350 4325) $PN CE10
J 2
(-5360 4335);
DISPLAY 0.489362 (-5360 4335);
PAINT MONO (-5360 4335);
FORCEPROP 0 LASTPIN (-5350 4225) $PN CL10
J 2
(-5360 4235);
DISPLAY 0.489362 (-5360 4235);
PAINT MONO (-5360 4235);
FORCEPROP 0 LASTPIN (-5350 4125) $PN CU10
J 2
(-5360 4135);
DISPLAY 0.489362 (-5360 4135);
PAINT MONO (-5360 4135);
FORCEPROP 0 LASTPIN (-5350 4025) $PN DC10
J 2
(-5360 4035);
DISPLAY 0.489362 (-5360 4035);
PAINT MONO (-5360 4035);
FORCEPROP 0 LASTPIN (-5350 3925) $PN BW9
J 2
(-5360 3935);
DISPLAY 0.489362 (-5360 3935);
PAINT MONO (-5360 3935);
FORCEPROP 0 LASTPIN (-5350 2175) $PN BL10
J 2
(-5360 2185);
DISPLAY 0.489362 (-5360 2185);
PAINT MONO (-5360 2185);
FORCEPROP 0 LASTPIN (-5350 1125) $PN BF11
J 2
(-5360 1135);
DISPLAY 0.489362 (-5360 1135);
PAINT MONO (-5360 1135);
FORCEPROP 2 LAST PART_TYPE SMLF
J 0
(-5200 6325);
DISPLAY 1.021277 (-5200 6325);
FORCEPROP 1 LAST MATERIAL IO
J 0
(-5195 6107);
DISPLAY 0.489362 (-5195 6107);
PAINT SKYBLUE (-5195 6107);
FORCEPROP 2 LAST VALUE SOCKET6096_13568-001
J 0
(-5200 6225);
DISPLAY 0.489362 (-5200 6225);
PAINT SKYBLUE (-5200 6225);
FORCEPROP 1 LAST PART_NUMBER DGA^6000030
J 0
(-5195 6234);
DISPLAY 0.489362 (-5195 6234);
PAINT SKYBLUE (-5195 6234);
FORCEPROP 2 LAST CDS_LIB pure_quanta
J 0
(-4550 3550);
DISPLAY INVISIBLE (-4550 3550);
FORCEPROP 1 LAST CDS_LMAN_SYM_OUTLINE -650,2525,650,-2525
J 0
(-4550 3550);
DISPLAY 0.468085 (-4550 3550);
PAINT GREEN (-4550 3550);
DISPLAY INVISIBLE (-4550 3550);
FORCEPROP 1 LAST NEEDS_NO_SIZE TRUE
J 0
(-4550 3550);
DISPLAY 0.723404 (-4550 3550);
PAINT GREEN (-4550 3550);
DISPLAY INVISIBLE (-4550 3550);
FORCEPROP 1 LAST PATH I159
J 0
(-4550 3550);
DISPLAY 0.723404 (-4550 3550);
PAINT GREEN (-4550 3550);
DISPLAY INVISIBLE (-4550 3550);
FORCEADD OFFPAGE..3
(-2550 5950);
FORCEPROP 2 LAST $XR0 108 
J 0
(-2336 5950);
DISPLAY 0.638298 (-2336 5950);
PAINT MONO (-2336 5950);
FORCEPROP 2 LAST PATH I160
J 0
(-2325 6000);
DISPLAY 1.021277 (-2325 6000);
DISPLAY INVISIBLE (-2325 6000);
FORCEPROP 1 LAST COMMENT_BODY TRUE
J 0
(-2600 5850);
DISPLAY 0.872340 (-2600 5850);
PAINT GREEN (-2600 5850);
DISPLAY INVISIBLE (-2600 5850);
FORCEPROP 1 LAST OFFPAGE TRUE
J 0
(-2225 5825);
DISPLAY 0.872340 (-2225 5825);
PAINT GREEN (-2225 5825);
DISPLAY INVISIBLE (-2225 5825);
FORCEPROP 2 LAST CDS_LIB mstr_standard
J 0
(-2550 5950);
DISPLAY 0.723404 (-2550 5950);
PAINT MONO (-2550 5950);
DISPLAY INVISIBLE (-2550 5950);
FORCEADD OFFPAGE..3
(-2550 4150);
FORCEPROP 2 LAST $XR0 108 
J 0
(-2336 4150);
DISPLAY 0.638298 (-2336 4150);
PAINT MONO (-2336 4150);
FORCEPROP 2 LAST PATH I161
J 0
(-2325 4200);
DISPLAY 1.021277 (-2325 4200);
DISPLAY INVISIBLE (-2325 4200);
FORCEPROP 1 LAST COMMENT_BODY TRUE
J 0
(-2600 4050);
DISPLAY 0.872340 (-2600 4050);
PAINT GREEN (-2600 4050);
DISPLAY INVISIBLE (-2600 4050);
FORCEPROP 1 LAST OFFPAGE TRUE
J 0
(-2225 4025);
DISPLAY 0.872340 (-2225 4025);
PAINT GREEN (-2225 4025);
DISPLAY INVISIBLE (-2225 4025);
FORCEPROP 2 LAST CDS_LIB mstr_standard
J 0
(-2550 4150);
DISPLAY 0.723404 (-2550 4150);
PAINT MONO (-2550 4150);
DISPLAY INVISIBLE (-2550 4150);
FORCEADD TAP..1
(-3275 5925);
FORCEPROP 3 LASTPIN (-3325 5925) SIG_NAME M_L_CPU1_SA_DQ<0>
J 0
(-3315 5935);
DISPLAY 0.659574 (-3315 5935);
PAINT MONO (-3315 5935);
DISPLAY INVISIBLE (-3315 5935);
FORCEPROP 1 LASTPIN (-3325 5925) BN 0
J 0
(-3337 5933);
DISPLAY 0.489362 (-3337 5933);
PAINT GREEN (-3337 5933);
FORCEPROP 2 LAST CDS_LIB mstr_standard
J 0
(-3275 5925);
DISPLAY 0.723404 (-3275 5925);
PAINT MONO (-3275 5925);
DISPLAY INVISIBLE (-3275 5925);
FORCEPROP 1 LAST BODY_TYPE PLUMBING
J 0
(-3275 5975);
DISPLAY 0.872340 (-3275 5975);
PAINT GREEN (-3275 5975);
DISPLAY INVISIBLE (-3275 5975);
FORCEPROP 1 LAST HDL_TAP TRUE
J 0
(-2950 5800);
DISPLAY 0.872340 (-2950 5800);
DISPLAY INVISIBLE (-2950 5800);
FORCEPROP 1 LAST PATH I162
J 0
(-3277 5925);
DISPLAY 0.872340 (-3277 5925);
PAINT GREEN (-3277 5925);
DISPLAY INVISIBLE (-3277 5925);
FORCEADD TAP..1
(-3275 5775);
FORCEPROP 3 LASTPIN (-3325 5775) SIG_NAME M_L_CPU1_SA_DQ<3>
J 0
(-3315 5785);
DISPLAY 0.659574 (-3315 5785);
PAINT MONO (-3315 5785);
DISPLAY INVISIBLE (-3315 5785);
FORCEPROP 1 LASTPIN (-3325 5775) BN 3
J 0
(-3337 5783);
DISPLAY 0.489362 (-3337 5783);
PAINT GREEN (-3337 5783);
FORCEPROP 2 LAST CDS_LIB mstr_standard
J 0
(-3275 5775);
DISPLAY 0.723404 (-3275 5775);
PAINT MONO (-3275 5775);
DISPLAY INVISIBLE (-3275 5775);
FORCEPROP 1 LAST BODY_TYPE PLUMBING
J 0
(-3275 5825);
DISPLAY 0.872340 (-3275 5825);
PAINT GREEN (-3275 5825);
DISPLAY INVISIBLE (-3275 5825);
FORCEPROP 1 LAST HDL_TAP TRUE
J 0
(-2950 5650);
DISPLAY 0.872340 (-2950 5650);
DISPLAY INVISIBLE (-2950 5650);
FORCEPROP 1 LAST PATH I163
J 0
(-3277 5775);
DISPLAY 0.872340 (-3277 5775);
PAINT GREEN (-3277 5775);
DISPLAY INVISIBLE (-3277 5775);
FORCEADD TAP..1
(-3275 5825);
FORCEPROP 3 LASTPIN (-3325 5825) SIG_NAME M_L_CPU1_SA_DQ<2>
J 0
(-3315 5835);
DISPLAY 0.659574 (-3315 5835);
PAINT MONO (-3315 5835);
DISPLAY INVISIBLE (-3315 5835);
FORCEPROP 1 LASTPIN (-3325 5825) BN 2
J 0
(-3337 5833);
DISPLAY 0.489362 (-3337 5833);
PAINT GREEN (-3337 5833);
FORCEPROP 2 LAST CDS_LIB mstr_standard
J 0
(-3275 5825);
DISPLAY 0.723404 (-3275 5825);
PAINT MONO (-3275 5825);
DISPLAY INVISIBLE (-3275 5825);
FORCEPROP 1 LAST BODY_TYPE PLUMBING
J 0
(-3275 5875);
DISPLAY 0.872340 (-3275 5875);
PAINT GREEN (-3275 5875);
DISPLAY INVISIBLE (-3275 5875);
FORCEPROP 1 LAST HDL_TAP TRUE
J 0
(-2950 5700);
DISPLAY 0.872340 (-2950 5700);
DISPLAY INVISIBLE (-2950 5700);
FORCEPROP 1 LAST PATH I164
J 0
(-3277 5825);
DISPLAY 0.872340 (-3277 5825);
PAINT GREEN (-3277 5825);
DISPLAY INVISIBLE (-3277 5825);
FORCEADD TAP..1
(-3275 5875);
FORCEPROP 3 LASTPIN (-3325 5875) SIG_NAME M_L_CPU1_SA_DQ<1>
J 0
(-3315 5885);
DISPLAY 0.659574 (-3315 5885);
PAINT MONO (-3315 5885);
DISPLAY INVISIBLE (-3315 5885);
FORCEPROP 1 LASTPIN (-3325 5875) BN 1
J 0
(-3337 5883);
DISPLAY 0.489362 (-3337 5883);
PAINT GREEN (-3337 5883);
FORCEPROP 2 LAST CDS_LIB mstr_standard
J 0
(-3275 5875);
DISPLAY 0.723404 (-3275 5875);
PAINT MONO (-3275 5875);
DISPLAY INVISIBLE (-3275 5875);
FORCEPROP 1 LAST BODY_TYPE PLUMBING
J 0
(-3275 5925);
DISPLAY 0.872340 (-3275 5925);
PAINT GREEN (-3275 5925);
DISPLAY INVISIBLE (-3275 5925);
FORCEPROP 1 LAST HDL_TAP TRUE
J 0
(-2950 5750);
DISPLAY 0.872340 (-2950 5750);
DISPLAY INVISIBLE (-2950 5750);
FORCEPROP 1 LAST PATH I165
J 0
(-3277 5875);
DISPLAY 0.872340 (-3277 5875);
PAINT GREEN (-3277 5875);
DISPLAY INVISIBLE (-3277 5875);
FORCEADD TAP..1
(-3275 5725);
FORCEPROP 3 LASTPIN (-3325 5725) SIG_NAME M_L_CPU1_SA_DQ<4>
J 0
(-3315 5735);
DISPLAY 0.659574 (-3315 5735);
PAINT MONO (-3315 5735);
DISPLAY INVISIBLE (-3315 5735);
FORCEPROP 1 LASTPIN (-3325 5725) BN 4
J 0
(-3337 5733);
DISPLAY 0.489362 (-3337 5733);
PAINT GREEN (-3337 5733);
FORCEPROP 2 LAST CDS_LIB mstr_standard
J 0
(-3275 5725);
DISPLAY 0.723404 (-3275 5725);
PAINT MONO (-3275 5725);
DISPLAY INVISIBLE (-3275 5725);
FORCEPROP 1 LAST BODY_TYPE PLUMBING
J 0
(-3275 5775);
DISPLAY 0.872340 (-3275 5775);
PAINT GREEN (-3275 5775);
DISPLAY INVISIBLE (-3275 5775);
FORCEPROP 1 LAST HDL_TAP TRUE
J 0
(-2950 5600);
DISPLAY 0.872340 (-2950 5600);
DISPLAY INVISIBLE (-2950 5600);
FORCEPROP 1 LAST PATH I166
J 0
(-3277 5725);
DISPLAY 0.872340 (-3277 5725);
PAINT GREEN (-3277 5725);
DISPLAY INVISIBLE (-3277 5725);
FORCEADD TAP..1
(-3275 5675);
FORCEPROP 3 LASTPIN (-3325 5675) SIG_NAME M_L_CPU1_SA_DQ<5>
J 0
(-3315 5685);
DISPLAY 0.659574 (-3315 5685);
PAINT MONO (-3315 5685);
DISPLAY INVISIBLE (-3315 5685);
FORCEPROP 1 LASTPIN (-3325 5675) BN 5
J 0
(-3337 5683);
DISPLAY 0.489362 (-3337 5683);
PAINT GREEN (-3337 5683);
FORCEPROP 2 LAST CDS_LIB mstr_standard
J 0
(-3275 5675);
DISPLAY 0.723404 (-3275 5675);
PAINT MONO (-3275 5675);
DISPLAY INVISIBLE (-3275 5675);
FORCEPROP 1 LAST BODY_TYPE PLUMBING
J 0
(-3275 5725);
DISPLAY 0.872340 (-3275 5725);
PAINT GREEN (-3275 5725);
DISPLAY INVISIBLE (-3275 5725);
FORCEPROP 1 LAST HDL_TAP TRUE
J 0
(-2950 5550);
DISPLAY 0.872340 (-2950 5550);
DISPLAY INVISIBLE (-2950 5550);
FORCEPROP 1 LAST PATH I167
J 0
(-3277 5675);
DISPLAY 0.872340 (-3277 5675);
PAINT GREEN (-3277 5675);
DISPLAY INVISIBLE (-3277 5675);
FORCEADD TAP..1
(-3275 5575);
FORCEPROP 3 LASTPIN (-3325 5575) SIG_NAME M_L_CPU1_SA_DQ<7>
J 0
(-3315 5585);
DISPLAY 0.659574 (-3315 5585);
PAINT MONO (-3315 5585);
DISPLAY INVISIBLE (-3315 5585);
FORCEPROP 1 LASTPIN (-3325 5575) BN 7
J 0
(-3337 5583);
DISPLAY 0.489362 (-3337 5583);
PAINT GREEN (-3337 5583);
FORCEPROP 2 LAST CDS_LIB mstr_standard
J 0
(-3275 5575);
DISPLAY 0.723404 (-3275 5575);
PAINT MONO (-3275 5575);
DISPLAY INVISIBLE (-3275 5575);
FORCEPROP 1 LAST BODY_TYPE PLUMBING
J 0
(-3275 5625);
DISPLAY 0.872340 (-3275 5625);
PAINT GREEN (-3275 5625);
DISPLAY INVISIBLE (-3275 5625);
FORCEPROP 1 LAST HDL_TAP TRUE
J 0
(-2950 5450);
DISPLAY 0.872340 (-2950 5450);
DISPLAY INVISIBLE (-2950 5450);
FORCEPROP 1 LAST PATH I168
J 0
(-3277 5575);
DISPLAY 0.872340 (-3277 5575);
PAINT GREEN (-3277 5575);
DISPLAY INVISIBLE (-3277 5575);
FORCEADD TAP..1
(-3275 5625);
FORCEPROP 3 LASTPIN (-3325 5625) SIG_NAME M_L_CPU1_SA_DQ<6>
J 0
(-3315 5635);
DISPLAY 0.659574 (-3315 5635);
PAINT MONO (-3315 5635);
DISPLAY INVISIBLE (-3315 5635);
FORCEPROP 1 LASTPIN (-3325 5625) BN 6
J 0
(-3337 5633);
DISPLAY 0.489362 (-3337 5633);
PAINT GREEN (-3337 5633);
FORCEPROP 2 LAST CDS_LIB mstr_standard
J 0
(-3275 5625);
DISPLAY 0.723404 (-3275 5625);
PAINT MONO (-3275 5625);
DISPLAY INVISIBLE (-3275 5625);
FORCEPROP 1 LAST BODY_TYPE PLUMBING
J 0
(-3275 5675);
DISPLAY 0.872340 (-3275 5675);
PAINT GREEN (-3275 5675);
DISPLAY INVISIBLE (-3275 5675);
FORCEPROP 1 LAST HDL_TAP TRUE
J 0
(-2950 5500);
DISPLAY 0.872340 (-2950 5500);
DISPLAY INVISIBLE (-2950 5500);
FORCEPROP 1 LAST PATH I169
J 0
(-3277 5625);
DISPLAY 0.872340 (-3277 5625);
PAINT GREEN (-3277 5625);
DISPLAY INVISIBLE (-3277 5625);
FORCEADD TAP..1
(-3275 5425);
FORCEPROP 3 LASTPIN (-3325 5425) SIG_NAME M_L_CPU1_SA_DQ<9>
J 0
(-3315 5435);
DISPLAY 0.659574 (-3315 5435);
PAINT MONO (-3315 5435);
DISPLAY INVISIBLE (-3315 5435);
FORCEPROP 1 LASTPIN (-3325 5425) BN 9
J 0
(-3337 5433);
DISPLAY 0.489362 (-3337 5433);
PAINT GREEN (-3337 5433);
FORCEPROP 2 LAST CDS_LIB mstr_standard
J 0
(-3275 5425);
DISPLAY 0.723404 (-3275 5425);
PAINT MONO (-3275 5425);
DISPLAY INVISIBLE (-3275 5425);
FORCEPROP 1 LAST BODY_TYPE PLUMBING
J 0
(-3275 5475);
DISPLAY 0.872340 (-3275 5475);
PAINT GREEN (-3275 5475);
DISPLAY INVISIBLE (-3275 5475);
FORCEPROP 1 LAST HDL_TAP TRUE
J 0
(-2950 5300);
DISPLAY 0.872340 (-2950 5300);
DISPLAY INVISIBLE (-2950 5300);
FORCEPROP 1 LAST PATH I170
J 0
(-3277 5425);
DISPLAY 0.872340 (-3277 5425);
PAINT GREEN (-3277 5425);
DISPLAY INVISIBLE (-3277 5425);
FORCEADD TAP..1
(-3275 5475);
FORCEPROP 3 LASTPIN (-3325 5475) SIG_NAME M_L_CPU1_SA_DQ<8>
J 0
(-3315 5485);
DISPLAY 0.659574 (-3315 5485);
PAINT MONO (-3315 5485);
DISPLAY INVISIBLE (-3315 5485);
FORCEPROP 1 LASTPIN (-3325 5475) BN 8
J 0
(-3337 5483);
DISPLAY 0.489362 (-3337 5483);
PAINT GREEN (-3337 5483);
FORCEPROP 2 LAST CDS_LIB mstr_standard
J 0
(-3275 5475);
DISPLAY 0.723404 (-3275 5475);
PAINT MONO (-3275 5475);
DISPLAY INVISIBLE (-3275 5475);
FORCEPROP 1 LAST BODY_TYPE PLUMBING
J 0
(-3275 5525);
DISPLAY 0.872340 (-3275 5525);
PAINT GREEN (-3275 5525);
DISPLAY INVISIBLE (-3275 5525);
FORCEPROP 1 LAST HDL_TAP TRUE
J 0
(-2950 5350);
DISPLAY 0.872340 (-2950 5350);
DISPLAY INVISIBLE (-2950 5350);
FORCEPROP 1 LAST PATH I171
J 0
(-3277 5475);
DISPLAY 0.872340 (-3277 5475);
PAINT GREEN (-3277 5475);
DISPLAY INVISIBLE (-3277 5475);
FORCEADD TAP..1
(-3275 5375);
FORCEPROP 3 LASTPIN (-3325 5375) SIG_NAME M_L_CPU1_SA_DQ<10>
J 0
(-3315 5385);
DISPLAY 0.659574 (-3315 5385);
PAINT MONO (-3315 5385);
DISPLAY INVISIBLE (-3315 5385);
FORCEPROP 1 LASTPIN (-3325 5375) BN 10
J 0
(-3337 5383);
DISPLAY 0.489362 (-3337 5383);
PAINT GREEN (-3337 5383);
FORCEPROP 2 LAST CDS_LIB mstr_standard
J 0
(-3275 5375);
DISPLAY 0.723404 (-3275 5375);
PAINT MONO (-3275 5375);
DISPLAY INVISIBLE (-3275 5375);
FORCEPROP 1 LAST BODY_TYPE PLUMBING
J 0
(-3275 5425);
DISPLAY 0.872340 (-3275 5425);
PAINT GREEN (-3275 5425);
DISPLAY INVISIBLE (-3275 5425);
FORCEPROP 1 LAST HDL_TAP TRUE
J 0
(-2950 5250);
DISPLAY 0.872340 (-2950 5250);
DISPLAY INVISIBLE (-2950 5250);
FORCEPROP 1 LAST PATH I172
J 0
(-3277 5375);
DISPLAY 0.872340 (-3277 5375);
PAINT GREEN (-3277 5375);
DISPLAY INVISIBLE (-3277 5375);
FORCEADD TAP..1
(-3275 5325);
FORCEPROP 3 LASTPIN (-3325 5325) SIG_NAME M_L_CPU1_SA_DQ<11>
J 0
(-3315 5335);
DISPLAY 0.659574 (-3315 5335);
PAINT MONO (-3315 5335);
DISPLAY INVISIBLE (-3315 5335);
FORCEPROP 1 LASTPIN (-3325 5325) BN 11
J 0
(-3337 5333);
DISPLAY 0.489362 (-3337 5333);
PAINT GREEN (-3337 5333);
FORCEPROP 2 LAST CDS_LIB mstr_standard
J 0
(-3275 5325);
DISPLAY 0.723404 (-3275 5325);
PAINT MONO (-3275 5325);
DISPLAY INVISIBLE (-3275 5325);
FORCEPROP 1 LAST BODY_TYPE PLUMBING
J 0
(-3275 5375);
DISPLAY 0.872340 (-3275 5375);
PAINT GREEN (-3275 5375);
DISPLAY INVISIBLE (-3275 5375);
FORCEPROP 1 LAST HDL_TAP TRUE
J 0
(-2950 5200);
DISPLAY 0.872340 (-2950 5200);
DISPLAY INVISIBLE (-2950 5200);
FORCEPROP 1 LAST PATH I173
J 0
(-3277 5325);
DISPLAY 0.872340 (-3277 5325);
PAINT GREEN (-3277 5325);
DISPLAY INVISIBLE (-3277 5325);
FORCEADD TAP..1
(-3275 5275);
FORCEPROP 3 LASTPIN (-3325 5275) SIG_NAME M_L_CPU1_SA_DQ<12>
J 0
(-3315 5285);
DISPLAY 0.659574 (-3315 5285);
PAINT MONO (-3315 5285);
DISPLAY INVISIBLE (-3315 5285);
FORCEPROP 1 LASTPIN (-3325 5275) BN 12
J 0
(-3337 5283);
DISPLAY 0.489362 (-3337 5283);
PAINT GREEN (-3337 5283);
FORCEPROP 2 LAST CDS_LIB mstr_standard
J 0
(-3275 5275);
DISPLAY 0.723404 (-3275 5275);
PAINT MONO (-3275 5275);
DISPLAY INVISIBLE (-3275 5275);
FORCEPROP 1 LAST BODY_TYPE PLUMBING
J 0
(-3275 5325);
DISPLAY 0.872340 (-3275 5325);
PAINT GREEN (-3275 5325);
DISPLAY INVISIBLE (-3275 5325);
FORCEPROP 1 LAST HDL_TAP TRUE
J 0
(-2950 5150);
DISPLAY 0.872340 (-2950 5150);
DISPLAY INVISIBLE (-2950 5150);
FORCEPROP 1 LAST PATH I174
J 0
(-3277 5275);
DISPLAY 0.872340 (-3277 5275);
PAINT GREEN (-3277 5275);
DISPLAY INVISIBLE (-3277 5275);
FORCEADD TAP..1
(-3275 5225);
FORCEPROP 3 LASTPIN (-3325 5225) SIG_NAME M_L_CPU1_SA_DQ<13>
J 0
(-3315 5235);
DISPLAY 0.659574 (-3315 5235);
PAINT MONO (-3315 5235);
DISPLAY INVISIBLE (-3315 5235);
FORCEPROP 1 LASTPIN (-3325 5225) BN 13
J 0
(-3337 5233);
DISPLAY 0.489362 (-3337 5233);
PAINT GREEN (-3337 5233);
FORCEPROP 2 LAST CDS_LIB mstr_standard
J 0
(-3275 5225);
DISPLAY 0.723404 (-3275 5225);
PAINT MONO (-3275 5225);
DISPLAY INVISIBLE (-3275 5225);
FORCEPROP 1 LAST BODY_TYPE PLUMBING
J 0
(-3275 5275);
DISPLAY 0.872340 (-3275 5275);
PAINT GREEN (-3275 5275);
DISPLAY INVISIBLE (-3275 5275);
FORCEPROP 1 LAST HDL_TAP TRUE
J 0
(-2950 5100);
DISPLAY 0.872340 (-2950 5100);
DISPLAY INVISIBLE (-2950 5100);
FORCEPROP 1 LAST PATH I175
J 0
(-3277 5225);
DISPLAY 0.872340 (-3277 5225);
PAINT GREEN (-3277 5225);
DISPLAY INVISIBLE (-3277 5225);
FORCEADD TAP..1
(-3275 5125);
FORCEPROP 3 LASTPIN (-3325 5125) SIG_NAME M_L_CPU1_SA_DQ<15>
J 0
(-3315 5135);
DISPLAY 0.659574 (-3315 5135);
PAINT MONO (-3315 5135);
DISPLAY INVISIBLE (-3315 5135);
FORCEPROP 1 LASTPIN (-3325 5125) BN 15
J 0
(-3337 5133);
DISPLAY 0.489362 (-3337 5133);
PAINT GREEN (-3337 5133);
FORCEPROP 2 LAST CDS_LIB mstr_standard
J 0
(-3275 5125);
DISPLAY 0.723404 (-3275 5125);
PAINT MONO (-3275 5125);
DISPLAY INVISIBLE (-3275 5125);
FORCEPROP 1 LAST BODY_TYPE PLUMBING
J 0
(-3275 5175);
DISPLAY 0.872340 (-3275 5175);
PAINT GREEN (-3275 5175);
DISPLAY INVISIBLE (-3275 5175);
FORCEPROP 1 LAST HDL_TAP TRUE
J 0
(-2950 5000);
DISPLAY 0.872340 (-2950 5000);
DISPLAY INVISIBLE (-2950 5000);
FORCEPROP 1 LAST PATH I176
J 0
(-3277 5125);
DISPLAY 0.872340 (-3277 5125);
PAINT GREEN (-3277 5125);
DISPLAY INVISIBLE (-3277 5125);
FORCEADD TAP..1
(-3275 5175);
FORCEPROP 3 LASTPIN (-3325 5175) SIG_NAME M_L_CPU1_SA_DQ<14>
J 0
(-3315 5185);
DISPLAY 0.659574 (-3315 5185);
PAINT MONO (-3315 5185);
DISPLAY INVISIBLE (-3315 5185);
FORCEPROP 1 LASTPIN (-3325 5175) BN 14
J 0
(-3337 5183);
DISPLAY 0.489362 (-3337 5183);
PAINT GREEN (-3337 5183);
FORCEPROP 2 LAST CDS_LIB mstr_standard
J 0
(-3275 5175);
DISPLAY 0.723404 (-3275 5175);
PAINT MONO (-3275 5175);
DISPLAY INVISIBLE (-3275 5175);
FORCEPROP 1 LAST BODY_TYPE PLUMBING
J 0
(-3275 5225);
DISPLAY 0.872340 (-3275 5225);
PAINT GREEN (-3275 5225);
DISPLAY INVISIBLE (-3275 5225);
FORCEPROP 1 LAST HDL_TAP TRUE
J 0
(-2950 5050);
DISPLAY 0.872340 (-2950 5050);
DISPLAY INVISIBLE (-2950 5050);
FORCEPROP 1 LAST PATH I177
J 0
(-3277 5175);
DISPLAY 0.872340 (-3277 5175);
PAINT GREEN (-3277 5175);
DISPLAY INVISIBLE (-3277 5175);
FORCEADD TAP..1
(-3275 5025);
FORCEPROP 3 LASTPIN (-3325 5025) SIG_NAME M_L_CPU1_SA_DQ<16>
J 0
(-3315 5035);
DISPLAY 0.659574 (-3315 5035);
PAINT MONO (-3315 5035);
DISPLAY INVISIBLE (-3315 5035);
FORCEPROP 1 LASTPIN (-3325 5025) BN 16
J 0
(-3337 5033);
DISPLAY 0.489362 (-3337 5033);
PAINT GREEN (-3337 5033);
FORCEPROP 2 LAST CDS_LIB mstr_standard
J 0
(-3275 5025);
DISPLAY 0.723404 (-3275 5025);
PAINT MONO (-3275 5025);
DISPLAY INVISIBLE (-3275 5025);
FORCEPROP 1 LAST BODY_TYPE PLUMBING
J 0
(-3275 5075);
DISPLAY 0.872340 (-3275 5075);
PAINT GREEN (-3275 5075);
DISPLAY INVISIBLE (-3275 5075);
FORCEPROP 1 LAST HDL_TAP TRUE
J 0
(-2950 4900);
DISPLAY 0.872340 (-2950 4900);
DISPLAY INVISIBLE (-2950 4900);
FORCEPROP 1 LAST PATH I178
J 0
(-3277 5025);
DISPLAY 0.872340 (-3277 5025);
PAINT GREEN (-3277 5025);
DISPLAY INVISIBLE (-3277 5025);
FORCEADD TAP..1
(-3275 4875);
FORCEPROP 3 LASTPIN (-3325 4875) SIG_NAME M_L_CPU1_SA_DQ<19>
J 0
(-3315 4885);
DISPLAY 0.659574 (-3315 4885);
PAINT MONO (-3315 4885);
DISPLAY INVISIBLE (-3315 4885);
FORCEPROP 1 LASTPIN (-3325 4875) BN 19
J 0
(-3337 4883);
DISPLAY 0.489362 (-3337 4883);
PAINT GREEN (-3337 4883);
FORCEPROP 2 LAST CDS_LIB mstr_standard
J 0
(-3275 4875);
DISPLAY 0.723404 (-3275 4875);
PAINT MONO (-3275 4875);
DISPLAY INVISIBLE (-3275 4875);
FORCEPROP 1 LAST BODY_TYPE PLUMBING
J 0
(-3275 4925);
DISPLAY 0.872340 (-3275 4925);
PAINT GREEN (-3275 4925);
DISPLAY INVISIBLE (-3275 4925);
FORCEPROP 1 LAST HDL_TAP TRUE
J 0
(-2950 4750);
DISPLAY 0.872340 (-2950 4750);
DISPLAY INVISIBLE (-2950 4750);
FORCEPROP 1 LAST PATH I179
J 0
(-3277 4875);
DISPLAY 0.872340 (-3277 4875);
PAINT GREEN (-3277 4875);
DISPLAY INVISIBLE (-3277 4875);
FORCEADD TAP..1
(-3275 4925);
FORCEPROP 3 LASTPIN (-3325 4925) SIG_NAME M_L_CPU1_SA_DQ<18>
J 0
(-3315 4935);
DISPLAY 0.659574 (-3315 4935);
PAINT MONO (-3315 4935);
DISPLAY INVISIBLE (-3315 4935);
FORCEPROP 1 LASTPIN (-3325 4925) BN 18
J 0
(-3337 4933);
DISPLAY 0.489362 (-3337 4933);
PAINT GREEN (-3337 4933);
FORCEPROP 2 LAST CDS_LIB mstr_standard
J 0
(-3275 4925);
DISPLAY 0.723404 (-3275 4925);
PAINT MONO (-3275 4925);
DISPLAY INVISIBLE (-3275 4925);
FORCEPROP 1 LAST BODY_TYPE PLUMBING
J 0
(-3275 4975);
DISPLAY 0.872340 (-3275 4975);
PAINT GREEN (-3275 4975);
DISPLAY INVISIBLE (-3275 4975);
FORCEPROP 1 LAST HDL_TAP TRUE
J 0
(-2950 4800);
DISPLAY 0.872340 (-2950 4800);
DISPLAY INVISIBLE (-2950 4800);
FORCEPROP 1 LAST PATH I180
J 0
(-3277 4925);
DISPLAY 0.872340 (-3277 4925);
PAINT GREEN (-3277 4925);
DISPLAY INVISIBLE (-3277 4925);
FORCEADD TAP..1
(-3275 4975);
FORCEPROP 3 LASTPIN (-3325 4975) SIG_NAME M_L_CPU1_SA_DQ<17>
J 0
(-3315 4985);
DISPLAY 0.659574 (-3315 4985);
PAINT MONO (-3315 4985);
DISPLAY INVISIBLE (-3315 4985);
FORCEPROP 1 LASTPIN (-3325 4975) BN 17
J 0
(-3337 4983);
DISPLAY 0.489362 (-3337 4983);
PAINT GREEN (-3337 4983);
FORCEPROP 2 LAST CDS_LIB mstr_standard
J 0
(-3275 4975);
DISPLAY 0.723404 (-3275 4975);
PAINT MONO (-3275 4975);
DISPLAY INVISIBLE (-3275 4975);
FORCEPROP 1 LAST BODY_TYPE PLUMBING
J 0
(-3275 5025);
DISPLAY 0.872340 (-3275 5025);
PAINT GREEN (-3275 5025);
DISPLAY INVISIBLE (-3275 5025);
FORCEPROP 1 LAST HDL_TAP TRUE
J 0
(-2950 4850);
DISPLAY 0.872340 (-2950 4850);
DISPLAY INVISIBLE (-2950 4850);
FORCEPROP 1 LAST PATH I181
J 0
(-3277 4975);
DISPLAY 0.872340 (-3277 4975);
PAINT GREEN (-3277 4975);
DISPLAY INVISIBLE (-3277 4975);
FORCEADD TAP..1
(-3275 4825);
FORCEPROP 3 LASTPIN (-3325 4825) SIG_NAME M_L_CPU1_SA_DQ<20>
J 0
(-3315 4835);
DISPLAY 0.659574 (-3315 4835);
PAINT MONO (-3315 4835);
DISPLAY INVISIBLE (-3315 4835);
FORCEPROP 1 LASTPIN (-3325 4825) BN 20
J 0
(-3337 4833);
DISPLAY 0.489362 (-3337 4833);
PAINT GREEN (-3337 4833);
FORCEPROP 2 LAST CDS_LIB mstr_standard
J 0
(-3275 4825);
DISPLAY 0.723404 (-3275 4825);
PAINT MONO (-3275 4825);
DISPLAY INVISIBLE (-3275 4825);
FORCEPROP 1 LAST BODY_TYPE PLUMBING
J 0
(-3275 4875);
DISPLAY 0.872340 (-3275 4875);
PAINT GREEN (-3275 4875);
DISPLAY INVISIBLE (-3275 4875);
FORCEPROP 1 LAST HDL_TAP TRUE
J 0
(-2950 4700);
DISPLAY 0.872340 (-2950 4700);
DISPLAY INVISIBLE (-2950 4700);
FORCEPROP 1 LAST PATH I182
J 0
(-3277 4825);
DISPLAY 0.872340 (-3277 4825);
PAINT GREEN (-3277 4825);
DISPLAY INVISIBLE (-3277 4825);
FORCEADD TAP..1
(-3275 4775);
FORCEPROP 3 LASTPIN (-3325 4775) SIG_NAME M_L_CPU1_SA_DQ<21>
J 0
(-3315 4785);
DISPLAY 0.659574 (-3315 4785);
PAINT MONO (-3315 4785);
DISPLAY INVISIBLE (-3315 4785);
FORCEPROP 1 LASTPIN (-3325 4775) BN 21
J 0
(-3337 4783);
DISPLAY 0.489362 (-3337 4783);
PAINT GREEN (-3337 4783);
FORCEPROP 2 LAST CDS_LIB mstr_standard
J 0
(-3275 4775);
DISPLAY 0.723404 (-3275 4775);
PAINT MONO (-3275 4775);
DISPLAY INVISIBLE (-3275 4775);
FORCEPROP 1 LAST BODY_TYPE PLUMBING
J 0
(-3275 4825);
DISPLAY 0.872340 (-3275 4825);
PAINT GREEN (-3275 4825);
DISPLAY INVISIBLE (-3275 4825);
FORCEPROP 1 LAST HDL_TAP TRUE
J 0
(-2950 4650);
DISPLAY 0.872340 (-2950 4650);
DISPLAY INVISIBLE (-2950 4650);
FORCEPROP 1 LAST PATH I183
J 0
(-3277 4775);
DISPLAY 0.872340 (-3277 4775);
PAINT GREEN (-3277 4775);
DISPLAY INVISIBLE (-3277 4775);
FORCEADD TAP..1
(-3275 4675);
FORCEPROP 3 LASTPIN (-3325 4675) SIG_NAME M_L_CPU1_SA_DQ<23>
J 0
(-3315 4685);
DISPLAY 0.659574 (-3315 4685);
PAINT MONO (-3315 4685);
DISPLAY INVISIBLE (-3315 4685);
FORCEPROP 1 LASTPIN (-3325 4675) BN 23
J 0
(-3337 4683);
DISPLAY 0.489362 (-3337 4683);
PAINT GREEN (-3337 4683);
FORCEPROP 2 LAST CDS_LIB mstr_standard
J 0
(-3275 4675);
DISPLAY 0.723404 (-3275 4675);
PAINT MONO (-3275 4675);
DISPLAY INVISIBLE (-3275 4675);
FORCEPROP 1 LAST BODY_TYPE PLUMBING
J 0
(-3275 4725);
DISPLAY 0.872340 (-3275 4725);
PAINT GREEN (-3275 4725);
DISPLAY INVISIBLE (-3275 4725);
FORCEPROP 1 LAST HDL_TAP TRUE
J 0
(-2950 4550);
DISPLAY 0.872340 (-2950 4550);
DISPLAY INVISIBLE (-2950 4550);
FORCEPROP 1 LAST PATH I184
J 0
(-3277 4675);
DISPLAY 0.872340 (-3277 4675);
PAINT GREEN (-3277 4675);
DISPLAY INVISIBLE (-3277 4675);
FORCEADD TAP..1
(-3275 4725);
FORCEPROP 3 LASTPIN (-3325 4725) SIG_NAME M_L_CPU1_SA_DQ<22>
J 0
(-3315 4735);
DISPLAY 0.659574 (-3315 4735);
PAINT MONO (-3315 4735);
DISPLAY INVISIBLE (-3315 4735);
FORCEPROP 1 LASTPIN (-3325 4725) BN 22
J 0
(-3337 4733);
DISPLAY 0.489362 (-3337 4733);
PAINT GREEN (-3337 4733);
FORCEPROP 2 LAST CDS_LIB mstr_standard
J 0
(-3275 4725);
DISPLAY 0.723404 (-3275 4725);
PAINT MONO (-3275 4725);
DISPLAY INVISIBLE (-3275 4725);
FORCEPROP 1 LAST BODY_TYPE PLUMBING
J 0
(-3275 4775);
DISPLAY 0.872340 (-3275 4775);
PAINT GREEN (-3275 4775);
DISPLAY INVISIBLE (-3275 4775);
FORCEPROP 1 LAST HDL_TAP TRUE
J 0
(-2950 4600);
DISPLAY 0.872340 (-2950 4600);
DISPLAY INVISIBLE (-2950 4600);
FORCEPROP 1 LAST PATH I185
J 0
(-3277 4725);
DISPLAY 0.872340 (-3277 4725);
PAINT GREEN (-3277 4725);
DISPLAY INVISIBLE (-3277 4725);
FORCEADD TAP..1
(-3275 4525);
FORCEPROP 3 LASTPIN (-3325 4525) SIG_NAME M_L_CPU1_SA_DQ<25>
J 0
(-3315 4535);
DISPLAY 0.659574 (-3315 4535);
PAINT MONO (-3315 4535);
DISPLAY INVISIBLE (-3315 4535);
FORCEPROP 1 LASTPIN (-3325 4525) BN 25
J 0
(-3337 4533);
DISPLAY 0.489362 (-3337 4533);
PAINT GREEN (-3337 4533);
FORCEPROP 2 LAST CDS_LIB mstr_standard
J 0
(-3275 4525);
DISPLAY 0.723404 (-3275 4525);
PAINT MONO (-3275 4525);
DISPLAY INVISIBLE (-3275 4525);
FORCEPROP 1 LAST BODY_TYPE PLUMBING
J 0
(-3275 4575);
DISPLAY 0.872340 (-3275 4575);
PAINT GREEN (-3275 4575);
DISPLAY INVISIBLE (-3275 4575);
FORCEPROP 1 LAST HDL_TAP TRUE
J 0
(-2950 4400);
DISPLAY 0.872340 (-2950 4400);
DISPLAY INVISIBLE (-2950 4400);
FORCEPROP 1 LAST PATH I186
J 0
(-3277 4525);
DISPLAY 0.872340 (-3277 4525);
PAINT GREEN (-3277 4525);
DISPLAY INVISIBLE (-3277 4525);
FORCEADD TAP..1
(-3275 4575);
FORCEPROP 3 LASTPIN (-3325 4575) SIG_NAME M_L_CPU1_SA_DQ<24>
J 0
(-3315 4585);
DISPLAY 0.659574 (-3315 4585);
PAINT MONO (-3315 4585);
DISPLAY INVISIBLE (-3315 4585);
FORCEPROP 1 LASTPIN (-3325 4575) BN 24
J 0
(-3337 4583);
DISPLAY 0.489362 (-3337 4583);
PAINT GREEN (-3337 4583);
FORCEPROP 2 LAST CDS_LIB mstr_standard
J 0
(-3275 4575);
DISPLAY 0.723404 (-3275 4575);
PAINT MONO (-3275 4575);
DISPLAY INVISIBLE (-3275 4575);
FORCEPROP 1 LAST BODY_TYPE PLUMBING
J 0
(-3275 4625);
DISPLAY 0.872340 (-3275 4625);
PAINT GREEN (-3275 4625);
DISPLAY INVISIBLE (-3275 4625);
FORCEPROP 1 LAST HDL_TAP TRUE
J 0
(-2950 4450);
DISPLAY 0.872340 (-2950 4450);
DISPLAY INVISIBLE (-2950 4450);
FORCEPROP 1 LAST PATH I187
J 0
(-3277 4575);
DISPLAY 0.872340 (-3277 4575);
PAINT GREEN (-3277 4575);
DISPLAY INVISIBLE (-3277 4575);
FORCEADD TAP..1
(-3275 4375);
FORCEPROP 3 LASTPIN (-3325 4375) SIG_NAME M_L_CPU1_SA_DQ<28>
J 0
(-3315 4385);
DISPLAY 0.659574 (-3315 4385);
PAINT MONO (-3315 4385);
DISPLAY INVISIBLE (-3315 4385);
FORCEPROP 1 LASTPIN (-3325 4375) BN 28
J 0
(-3337 4383);
DISPLAY 0.489362 (-3337 4383);
PAINT GREEN (-3337 4383);
FORCEPROP 2 LAST CDS_LIB mstr_standard
J 0
(-3275 4375);
DISPLAY 0.723404 (-3275 4375);
PAINT MONO (-3275 4375);
DISPLAY INVISIBLE (-3275 4375);
FORCEPROP 1 LAST BODY_TYPE PLUMBING
J 0
(-3275 4425);
DISPLAY 0.872340 (-3275 4425);
PAINT GREEN (-3275 4425);
DISPLAY INVISIBLE (-3275 4425);
FORCEPROP 1 LAST HDL_TAP TRUE
J 0
(-2950 4250);
DISPLAY 0.872340 (-2950 4250);
DISPLAY INVISIBLE (-2950 4250);
FORCEPROP 1 LAST PATH I188
J 0
(-3277 4375);
DISPLAY 0.872340 (-3277 4375);
PAINT GREEN (-3277 4375);
DISPLAY INVISIBLE (-3277 4375);
FORCEADD TAP..1
(-3275 4425);
FORCEPROP 3 LASTPIN (-3325 4425) SIG_NAME M_L_CPU1_SA_DQ<27>
J 0
(-3315 4435);
DISPLAY 0.659574 (-3315 4435);
PAINT MONO (-3315 4435);
DISPLAY INVISIBLE (-3315 4435);
FORCEPROP 1 LASTPIN (-3325 4425) BN 27
J 0
(-3337 4433);
DISPLAY 0.489362 (-3337 4433);
PAINT GREEN (-3337 4433);
FORCEPROP 2 LAST CDS_LIB mstr_standard
J 0
(-3275 4425);
DISPLAY 0.723404 (-3275 4425);
PAINT MONO (-3275 4425);
DISPLAY INVISIBLE (-3275 4425);
FORCEPROP 1 LAST BODY_TYPE PLUMBING
J 0
(-3275 4475);
DISPLAY 0.872340 (-3275 4475);
PAINT GREEN (-3275 4475);
DISPLAY INVISIBLE (-3275 4475);
FORCEPROP 1 LAST HDL_TAP TRUE
J 0
(-2950 4300);
DISPLAY 0.872340 (-2950 4300);
DISPLAY INVISIBLE (-2950 4300);
FORCEPROP 1 LAST PATH I189
J 0
(-3277 4425);
DISPLAY 0.872340 (-3277 4425);
PAINT GREEN (-3277 4425);
DISPLAY INVISIBLE (-3277 4425);
FORCEADD TAP..1
(-3275 4475);
FORCEPROP 3 LASTPIN (-3325 4475) SIG_NAME M_L_CPU1_SA_DQ<26>
J 0
(-3315 4485);
DISPLAY 0.659574 (-3315 4485);
PAINT MONO (-3315 4485);
DISPLAY INVISIBLE (-3315 4485);
FORCEPROP 1 LASTPIN (-3325 4475) BN 26
J 0
(-3337 4483);
DISPLAY 0.489362 (-3337 4483);
PAINT GREEN (-3337 4483);
FORCEPROP 2 LAST CDS_LIB mstr_standard
J 0
(-3275 4475);
DISPLAY 0.723404 (-3275 4475);
PAINT MONO (-3275 4475);
DISPLAY INVISIBLE (-3275 4475);
FORCEPROP 1 LAST BODY_TYPE PLUMBING
J 0
(-3275 4525);
DISPLAY 0.872340 (-3275 4525);
PAINT GREEN (-3275 4525);
DISPLAY INVISIBLE (-3275 4525);
FORCEPROP 1 LAST HDL_TAP TRUE
J 0
(-2950 4350);
DISPLAY 0.872340 (-2950 4350);
DISPLAY INVISIBLE (-2950 4350);
FORCEPROP 1 LAST PATH I190
J 0
(-3277 4475);
DISPLAY 0.872340 (-3277 4475);
PAINT GREEN (-3277 4475);
DISPLAY INVISIBLE (-3277 4475);
FORCEADD TAP..1
(-3275 4325);
FORCEPROP 3 LASTPIN (-3325 4325) SIG_NAME M_L_CPU1_SA_DQ<29>
J 0
(-3315 4335);
DISPLAY 0.659574 (-3315 4335);
PAINT MONO (-3315 4335);
DISPLAY INVISIBLE (-3315 4335);
FORCEPROP 1 LASTPIN (-3325 4325) BN 29
J 0
(-3337 4333);
DISPLAY 0.489362 (-3337 4333);
PAINT GREEN (-3337 4333);
FORCEPROP 2 LAST CDS_LIB mstr_standard
J 0
(-3275 4325);
DISPLAY 0.723404 (-3275 4325);
PAINT MONO (-3275 4325);
DISPLAY INVISIBLE (-3275 4325);
FORCEPROP 1 LAST BODY_TYPE PLUMBING
J 0
(-3275 4375);
DISPLAY 0.872340 (-3275 4375);
PAINT GREEN (-3275 4375);
DISPLAY INVISIBLE (-3275 4375);
FORCEPROP 1 LAST HDL_TAP TRUE
J 0
(-2950 4200);
DISPLAY 0.872340 (-2950 4200);
DISPLAY INVISIBLE (-2950 4200);
FORCEPROP 1 LAST PATH I191
J 0
(-3277 4325);
DISPLAY 0.872340 (-3277 4325);
PAINT GREEN (-3277 4325);
DISPLAY INVISIBLE (-3277 4325);
FORCEADD TAP..1
(-3275 4225);
FORCEPROP 3 LASTPIN (-3325 4225) SIG_NAME M_L_CPU1_SA_DQ<31>
J 0
(-3315 4235);
DISPLAY 0.659574 (-3315 4235);
PAINT MONO (-3315 4235);
DISPLAY INVISIBLE (-3315 4235);
FORCEPROP 1 LASTPIN (-3325 4225) BN 31
J 0
(-3337 4233);
DISPLAY 0.489362 (-3337 4233);
PAINT GREEN (-3337 4233);
FORCEPROP 2 LAST CDS_LIB mstr_standard
J 0
(-3275 4225);
DISPLAY 0.723404 (-3275 4225);
PAINT MONO (-3275 4225);
DISPLAY INVISIBLE (-3275 4225);
FORCEPROP 1 LAST BODY_TYPE PLUMBING
J 0
(-3275 4275);
DISPLAY 0.872340 (-3275 4275);
PAINT GREEN (-3275 4275);
DISPLAY INVISIBLE (-3275 4275);
FORCEPROP 1 LAST HDL_TAP TRUE
J 0
(-2950 4100);
DISPLAY 0.872340 (-2950 4100);
DISPLAY INVISIBLE (-2950 4100);
FORCEPROP 1 LAST PATH I192
J 0
(-3277 4225);
DISPLAY 0.872340 (-3277 4225);
PAINT GREEN (-3277 4225);
DISPLAY INVISIBLE (-3277 4225);
FORCEADD TAP..1
(-3275 4275);
FORCEPROP 3 LASTPIN (-3325 4275) SIG_NAME M_L_CPU1_SA_DQ<30>
J 0
(-3315 4285);
DISPLAY 0.659574 (-3315 4285);
PAINT MONO (-3315 4285);
DISPLAY INVISIBLE (-3315 4285);
FORCEPROP 1 LASTPIN (-3325 4275) BN 30
J 0
(-3337 4283);
DISPLAY 0.489362 (-3337 4283);
PAINT GREEN (-3337 4283);
FORCEPROP 2 LAST CDS_LIB mstr_standard
J 0
(-3275 4275);
DISPLAY 0.723404 (-3275 4275);
PAINT MONO (-3275 4275);
DISPLAY INVISIBLE (-3275 4275);
FORCEPROP 1 LAST BODY_TYPE PLUMBING
J 0
(-3275 4325);
DISPLAY 0.872340 (-3275 4325);
PAINT GREEN (-3275 4325);
DISPLAY INVISIBLE (-3275 4325);
FORCEPROP 1 LAST HDL_TAP TRUE
J 0
(-2950 4150);
DISPLAY 0.872340 (-2950 4150);
DISPLAY INVISIBLE (-2950 4150);
FORCEPROP 1 LAST PATH I193
J 0
(-3277 4275);
DISPLAY 0.872340 (-3277 4275);
PAINT GREEN (-3277 4275);
DISPLAY INVISIBLE (-3277 4275);
FORCEADD TAP..1
(-3275 4125);
FORCEPROP 3 LASTPIN (-3325 4125) SIG_NAME M_L_CPU1_SB_DQ<0>
J 0
(-3315 4135);
DISPLAY 0.659574 (-3315 4135);
PAINT MONO (-3315 4135);
DISPLAY INVISIBLE (-3315 4135);
FORCEPROP 1 LASTPIN (-3325 4125) BN 0
J 0
(-3337 4133);
DISPLAY 0.489362 (-3337 4133);
PAINT GREEN (-3337 4133);
FORCEPROP 2 LAST CDS_LIB mstr_standard
J 0
(-3275 4125);
DISPLAY 0.723404 (-3275 4125);
PAINT MONO (-3275 4125);
DISPLAY INVISIBLE (-3275 4125);
FORCEPROP 1 LAST BODY_TYPE PLUMBING
J 0
(-3275 4175);
DISPLAY 0.872340 (-3275 4175);
PAINT GREEN (-3275 4175);
DISPLAY INVISIBLE (-3275 4175);
FORCEPROP 1 LAST HDL_TAP TRUE
J 0
(-2950 4000);
DISPLAY 0.872340 (-2950 4000);
DISPLAY INVISIBLE (-2950 4000);
FORCEPROP 1 LAST PATH I194
J 0
(-3277 4125);
DISPLAY 0.872340 (-3277 4125);
PAINT GREEN (-3277 4125);
DISPLAY INVISIBLE (-3277 4125);
FORCEADD OFFPAGE..6
R 2
(-2675 2375);
FORCEPROP 2 LAST $XR0 108 
J 0
(-2461 2375);
DISPLAY 0.638298 (-2461 2375);
PAINT MONO (-2461 2375);
FORCEPROP 2 LAST PATH I195
J 0
(-2450 2425);
DISPLAY 1.021277 (-2450 2425);
DISPLAY INVISIBLE (-2450 2425);
FORCEPROP 1 LAST COMMENT_BODY TRUE
J 2
(-2775 2300);
DISPLAY 0.872340 (-2775 2300);
PAINT GREEN (-2775 2300);
DISPLAY INVISIBLE (-2775 2300);
FORCEPROP 1 LAST OFFPAGE TRUE
J 2
(-3000 2250);
DISPLAY 0.872340 (-3000 2250);
PAINT GREEN (-3000 2250);
DISPLAY INVISIBLE (-3000 2250);
FORCEPROP 2 LAST CDS_LIB mstr_standard
J 2
(-2675 2375);
DISPLAY 0.723404 (-2675 2375);
PAINT MONO (-2675 2375);
DISPLAY INVISIBLE (-2675 2375);
FORCEADD TAP..1
(-3275 3975);
FORCEPROP 3 LASTPIN (-3325 3975) SIG_NAME M_L_CPU1_SB_DQ<3>
J 0
(-3315 3985);
DISPLAY 0.659574 (-3315 3985);
PAINT MONO (-3315 3985);
DISPLAY INVISIBLE (-3315 3985);
FORCEPROP 1 LASTPIN (-3325 3975) BN 3
J 0
(-3337 3983);
DISPLAY 0.489362 (-3337 3983);
PAINT GREEN (-3337 3983);
FORCEPROP 2 LAST CDS_LIB mstr_standard
J 0
(-3275 3975);
DISPLAY 0.723404 (-3275 3975);
PAINT MONO (-3275 3975);
DISPLAY INVISIBLE (-3275 3975);
FORCEPROP 1 LAST BODY_TYPE PLUMBING
J 0
(-3275 4025);
DISPLAY 0.872340 (-3275 4025);
PAINT GREEN (-3275 4025);
DISPLAY INVISIBLE (-3275 4025);
FORCEPROP 1 LAST HDL_TAP TRUE
J 0
(-2950 3850);
DISPLAY 0.872340 (-2950 3850);
DISPLAY INVISIBLE (-2950 3850);
FORCEPROP 1 LAST PATH I196
J 0
(-3277 3975);
DISPLAY 0.872340 (-3277 3975);
PAINT GREEN (-3277 3975);
DISPLAY INVISIBLE (-3277 3975);
FORCEADD TAP..1
(-3275 4075);
FORCEPROP 3 LASTPIN (-3325 4075) SIG_NAME M_L_CPU1_SB_DQ<1>
J 0
(-3315 4085);
DISPLAY 0.659574 (-3315 4085);
PAINT MONO (-3315 4085);
DISPLAY INVISIBLE (-3315 4085);
FORCEPROP 1 LASTPIN (-3325 4075) BN 1
J 0
(-3337 4083);
DISPLAY 0.489362 (-3337 4083);
PAINT GREEN (-3337 4083);
FORCEPROP 2 LAST CDS_LIB mstr_standard
J 0
(-3275 4075);
DISPLAY 0.723404 (-3275 4075);
PAINT MONO (-3275 4075);
DISPLAY INVISIBLE (-3275 4075);
FORCEPROP 1 LAST BODY_TYPE PLUMBING
J 0
(-3275 4125);
DISPLAY 0.872340 (-3275 4125);
PAINT GREEN (-3275 4125);
DISPLAY INVISIBLE (-3275 4125);
FORCEPROP 1 LAST HDL_TAP TRUE
J 0
(-2950 3950);
DISPLAY 0.872340 (-2950 3950);
DISPLAY INVISIBLE (-2950 3950);
FORCEPROP 1 LAST PATH I197
J 0
(-3277 4075);
DISPLAY 0.872340 (-3277 4075);
PAINT GREEN (-3277 4075);
DISPLAY INVISIBLE (-3277 4075);
FORCEADD TAP..1
(-3275 4025);
FORCEPROP 3 LASTPIN (-3325 4025) SIG_NAME M_L_CPU1_SB_DQ<2>
J 0
(-3315 4035);
DISPLAY 0.659574 (-3315 4035);
PAINT MONO (-3315 4035);
DISPLAY INVISIBLE (-3315 4035);
FORCEPROP 1 LASTPIN (-3325 4025) BN 2
J 0
(-3337 4033);
DISPLAY 0.489362 (-3337 4033);
PAINT GREEN (-3337 4033);
FORCEPROP 2 LAST CDS_LIB mstr_standard
J 0
(-3275 4025);
DISPLAY 0.723404 (-3275 4025);
PAINT MONO (-3275 4025);
DISPLAY INVISIBLE (-3275 4025);
FORCEPROP 1 LAST BODY_TYPE PLUMBING
J 0
(-3275 4075);
DISPLAY 0.872340 (-3275 4075);
PAINT GREEN (-3275 4075);
DISPLAY INVISIBLE (-3275 4075);
FORCEPROP 1 LAST HDL_TAP TRUE
J 0
(-2950 3900);
DISPLAY 0.872340 (-2950 3900);
DISPLAY INVISIBLE (-2950 3900);
FORCEPROP 1 LAST PATH I198
J 0
(-3277 4025);
DISPLAY 0.872340 (-3277 4025);
PAINT GREEN (-3277 4025);
DISPLAY INVISIBLE (-3277 4025);
FORCEADD TAP..1
(-3275 3875);
FORCEPROP 3 LASTPIN (-3325 3875) SIG_NAME M_L_CPU1_SB_DQ<5>
J 0
(-3315 3885);
DISPLAY 0.659574 (-3315 3885);
PAINT MONO (-3315 3885);
DISPLAY INVISIBLE (-3315 3885);
FORCEPROP 1 LASTPIN (-3325 3875) BN 5
J 0
(-3337 3883);
DISPLAY 0.489362 (-3337 3883);
PAINT GREEN (-3337 3883);
FORCEPROP 2 LAST CDS_LIB mstr_standard
J 0
(-3275 3875);
DISPLAY 0.723404 (-3275 3875);
PAINT MONO (-3275 3875);
DISPLAY INVISIBLE (-3275 3875);
FORCEPROP 1 LAST BODY_TYPE PLUMBING
J 0
(-3275 3925);
DISPLAY 0.872340 (-3275 3925);
PAINT GREEN (-3275 3925);
DISPLAY INVISIBLE (-3275 3925);
FORCEPROP 1 LAST HDL_TAP TRUE
J 0
(-2950 3750);
DISPLAY 0.872340 (-2950 3750);
DISPLAY INVISIBLE (-2950 3750);
FORCEPROP 1 LAST PATH I199
J 0
(-3277 3875);
DISPLAY 0.872340 (-3277 3875);
PAINT GREEN (-3277 3875);
DISPLAY INVISIBLE (-3277 3875);
FORCEADD TAP..1
(-3275 3925);
FORCEPROP 3 LASTPIN (-3325 3925) SIG_NAME M_L_CPU1_SB_DQ<4>
J 0
(-3315 3935);
DISPLAY 0.659574 (-3315 3935);
PAINT MONO (-3315 3935);
DISPLAY INVISIBLE (-3315 3935);
FORCEPROP 1 LASTPIN (-3325 3925) BN 4
J 0
(-3337 3933);
DISPLAY 0.489362 (-3337 3933);
PAINT GREEN (-3337 3933);
FORCEPROP 2 LAST CDS_LIB mstr_standard
J 0
(-3275 3925);
DISPLAY 0.723404 (-3275 3925);
PAINT MONO (-3275 3925);
DISPLAY INVISIBLE (-3275 3925);
FORCEPROP 1 LAST BODY_TYPE PLUMBING
J 0
(-3275 3975);
DISPLAY 0.872340 (-3275 3975);
PAINT GREEN (-3275 3975);
DISPLAY INVISIBLE (-3275 3975);
FORCEPROP 1 LAST HDL_TAP TRUE
J 0
(-2950 3800);
DISPLAY 0.872340 (-2950 3800);
DISPLAY INVISIBLE (-2950 3800);
FORCEPROP 1 LAST PATH I200
J 0
(-3277 3925);
DISPLAY 0.872340 (-3277 3925);
PAINT GREEN (-3277 3925);
DISPLAY INVISIBLE (-3277 3925);
FORCEADD TAP..1
(-3275 3775);
FORCEPROP 3 LASTPIN (-3325 3775) SIG_NAME M_L_CPU1_SB_DQ<7>
J 0
(-3315 3785);
DISPLAY 0.659574 (-3315 3785);
PAINT MONO (-3315 3785);
DISPLAY INVISIBLE (-3315 3785);
FORCEPROP 1 LASTPIN (-3325 3775) BN 7
J 0
(-3337 3783);
DISPLAY 0.489362 (-3337 3783);
PAINT GREEN (-3337 3783);
FORCEPROP 2 LAST CDS_LIB mstr_standard
J 0
(-3275 3775);
DISPLAY 0.723404 (-3275 3775);
PAINT MONO (-3275 3775);
DISPLAY INVISIBLE (-3275 3775);
FORCEPROP 1 LAST BODY_TYPE PLUMBING
J 0
(-3275 3825);
DISPLAY 0.872340 (-3275 3825);
PAINT GREEN (-3275 3825);
DISPLAY INVISIBLE (-3275 3825);
FORCEPROP 1 LAST HDL_TAP TRUE
J 0
(-2950 3650);
DISPLAY 0.872340 (-2950 3650);
DISPLAY INVISIBLE (-2950 3650);
FORCEPROP 1 LAST PATH I201
J 0
(-3277 3775);
DISPLAY 0.872340 (-3277 3775);
PAINT GREEN (-3277 3775);
DISPLAY INVISIBLE (-3277 3775);
FORCEADD TAP..1
(-3275 3825);
FORCEPROP 3 LASTPIN (-3325 3825) SIG_NAME M_L_CPU1_SB_DQ<6>
J 0
(-3315 3835);
DISPLAY 0.659574 (-3315 3835);
PAINT MONO (-3315 3835);
DISPLAY INVISIBLE (-3315 3835);
FORCEPROP 1 LASTPIN (-3325 3825) BN 6
J 0
(-3337 3833);
DISPLAY 0.489362 (-3337 3833);
PAINT GREEN (-3337 3833);
FORCEPROP 2 LAST CDS_LIB mstr_standard
J 0
(-3275 3825);
DISPLAY 0.723404 (-3275 3825);
PAINT MONO (-3275 3825);
DISPLAY INVISIBLE (-3275 3825);
FORCEPROP 1 LAST BODY_TYPE PLUMBING
J 0
(-3275 3875);
DISPLAY 0.872340 (-3275 3875);
PAINT GREEN (-3275 3875);
DISPLAY INVISIBLE (-3275 3875);
FORCEPROP 1 LAST HDL_TAP TRUE
J 0
(-2950 3700);
DISPLAY 0.872340 (-2950 3700);
DISPLAY INVISIBLE (-2950 3700);
FORCEPROP 1 LAST PATH I202
J 0
(-3277 3825);
DISPLAY 0.872340 (-3277 3825);
PAINT GREEN (-3277 3825);
DISPLAY INVISIBLE (-3277 3825);
FORCEADD TAP..1
(-3275 3625);
FORCEPROP 3 LASTPIN (-3325 3625) SIG_NAME M_L_CPU1_SB_DQ<9>
J 0
(-3315 3635);
DISPLAY 0.659574 (-3315 3635);
PAINT MONO (-3315 3635);
DISPLAY INVISIBLE (-3315 3635);
FORCEPROP 1 LASTPIN (-3325 3625) BN 9
J 0
(-3337 3633);
DISPLAY 0.489362 (-3337 3633);
PAINT GREEN (-3337 3633);
FORCEPROP 2 LAST CDS_LIB mstr_standard
J 0
(-3275 3625);
DISPLAY 0.723404 (-3275 3625);
PAINT MONO (-3275 3625);
DISPLAY INVISIBLE (-3275 3625);
FORCEPROP 1 LAST BODY_TYPE PLUMBING
J 0
(-3275 3675);
DISPLAY 0.872340 (-3275 3675);
PAINT GREEN (-3275 3675);
DISPLAY INVISIBLE (-3275 3675);
FORCEPROP 1 LAST HDL_TAP TRUE
J 0
(-2950 3500);
DISPLAY 0.872340 (-2950 3500);
DISPLAY INVISIBLE (-2950 3500);
FORCEPROP 1 LAST PATH I203
J 0
(-3277 3625);
DISPLAY 0.872340 (-3277 3625);
PAINT GREEN (-3277 3625);
DISPLAY INVISIBLE (-3277 3625);
FORCEADD TAP..1
(-3275 3675);
FORCEPROP 3 LASTPIN (-3325 3675) SIG_NAME M_L_CPU1_SB_DQ<8>
J 0
(-3315 3685);
DISPLAY 0.659574 (-3315 3685);
PAINT MONO (-3315 3685);
DISPLAY INVISIBLE (-3315 3685);
FORCEPROP 1 LASTPIN (-3325 3675) BN 8
J 0
(-3337 3683);
DISPLAY 0.489362 (-3337 3683);
PAINT GREEN (-3337 3683);
FORCEPROP 2 LAST CDS_LIB mstr_standard
J 0
(-3275 3675);
DISPLAY 0.723404 (-3275 3675);
PAINT MONO (-3275 3675);
DISPLAY INVISIBLE (-3275 3675);
FORCEPROP 1 LAST BODY_TYPE PLUMBING
J 0
(-3275 3725);
DISPLAY 0.872340 (-3275 3725);
PAINT GREEN (-3275 3725);
DISPLAY INVISIBLE (-3275 3725);
FORCEPROP 1 LAST HDL_TAP TRUE
J 0
(-2950 3550);
DISPLAY 0.872340 (-2950 3550);
DISPLAY INVISIBLE (-2950 3550);
FORCEPROP 1 LAST PATH I204
J 0
(-3277 3675);
DISPLAY 0.872340 (-3277 3675);
PAINT GREEN (-3277 3675);
DISPLAY INVISIBLE (-3277 3675);
FORCEADD TAP..1
(-3275 3475);
FORCEPROP 3 LASTPIN (-3325 3475) SIG_NAME M_L_CPU1_SB_DQ<12>
J 0
(-3315 3485);
DISPLAY 0.659574 (-3315 3485);
PAINT MONO (-3315 3485);
DISPLAY INVISIBLE (-3315 3485);
FORCEPROP 1 LASTPIN (-3325 3475) BN 12
J 0
(-3337 3483);
DISPLAY 0.489362 (-3337 3483);
PAINT GREEN (-3337 3483);
FORCEPROP 2 LAST CDS_LIB mstr_standard
J 0
(-3275 3475);
DISPLAY 0.723404 (-3275 3475);
PAINT MONO (-3275 3475);
DISPLAY INVISIBLE (-3275 3475);
FORCEPROP 1 LAST BODY_TYPE PLUMBING
J 0
(-3275 3525);
DISPLAY 0.872340 (-3275 3525);
PAINT GREEN (-3275 3525);
DISPLAY INVISIBLE (-3275 3525);
FORCEPROP 1 LAST HDL_TAP TRUE
J 0
(-2950 3350);
DISPLAY 0.872340 (-2950 3350);
DISPLAY INVISIBLE (-2950 3350);
FORCEPROP 1 LAST PATH I205
J 0
(-3277 3475);
DISPLAY 0.872340 (-3277 3475);
PAINT GREEN (-3277 3475);
DISPLAY INVISIBLE (-3277 3475);
FORCEADD TAP..1
(-3275 3575);
FORCEPROP 3 LASTPIN (-3325 3575) SIG_NAME M_L_CPU1_SB_DQ<10>
J 0
(-3315 3585);
DISPLAY 0.659574 (-3315 3585);
PAINT MONO (-3315 3585);
DISPLAY INVISIBLE (-3315 3585);
FORCEPROP 1 LASTPIN (-3325 3575) BN 10
J 0
(-3337 3583);
DISPLAY 0.489362 (-3337 3583);
PAINT GREEN (-3337 3583);
FORCEPROP 2 LAST CDS_LIB mstr_standard
J 0
(-3275 3575);
DISPLAY 0.723404 (-3275 3575);
PAINT MONO (-3275 3575);
DISPLAY INVISIBLE (-3275 3575);
FORCEPROP 1 LAST BODY_TYPE PLUMBING
J 0
(-3275 3625);
DISPLAY 0.872340 (-3275 3625);
PAINT GREEN (-3275 3625);
DISPLAY INVISIBLE (-3275 3625);
FORCEPROP 1 LAST HDL_TAP TRUE
J 0
(-2950 3450);
DISPLAY 0.872340 (-2950 3450);
DISPLAY INVISIBLE (-2950 3450);
FORCEPROP 1 LAST PATH I206
J 0
(-3277 3575);
DISPLAY 0.872340 (-3277 3575);
PAINT GREEN (-3277 3575);
DISPLAY INVISIBLE (-3277 3575);
FORCEADD TAP..1
(-3275 3525);
FORCEPROP 3 LASTPIN (-3325 3525) SIG_NAME M_L_CPU1_SB_DQ<11>
J 0
(-3315 3535);
DISPLAY 0.659574 (-3315 3535);
PAINT MONO (-3315 3535);
DISPLAY INVISIBLE (-3315 3535);
FORCEPROP 1 LASTPIN (-3325 3525) BN 11
J 0
(-3337 3533);
DISPLAY 0.489362 (-3337 3533);
PAINT GREEN (-3337 3533);
FORCEPROP 2 LAST CDS_LIB mstr_standard
J 0
(-3275 3525);
DISPLAY 0.723404 (-3275 3525);
PAINT MONO (-3275 3525);
DISPLAY INVISIBLE (-3275 3525);
FORCEPROP 1 LAST BODY_TYPE PLUMBING
J 0
(-3275 3575);
DISPLAY 0.872340 (-3275 3575);
PAINT GREEN (-3275 3575);
DISPLAY INVISIBLE (-3275 3575);
FORCEPROP 1 LAST HDL_TAP TRUE
J 0
(-2950 3400);
DISPLAY 0.872340 (-2950 3400);
DISPLAY INVISIBLE (-2950 3400);
FORCEPROP 1 LAST PATH I207
J 0
(-3277 3525);
DISPLAY 0.872340 (-3277 3525);
PAINT GREEN (-3277 3525);
DISPLAY INVISIBLE (-3277 3525);
FORCEADD TAP..1
(-3275 3375);
FORCEPROP 3 LASTPIN (-3325 3375) SIG_NAME M_L_CPU1_SB_DQ<14>
J 0
(-3315 3385);
DISPLAY 0.659574 (-3315 3385);
PAINT MONO (-3315 3385);
DISPLAY INVISIBLE (-3315 3385);
FORCEPROP 1 LASTPIN (-3325 3375) BN 14
J 0
(-3337 3383);
DISPLAY 0.489362 (-3337 3383);
PAINT GREEN (-3337 3383);
FORCEPROP 2 LAST CDS_LIB mstr_standard
J 0
(-3275 3375);
DISPLAY 0.723404 (-3275 3375);
PAINT MONO (-3275 3375);
DISPLAY INVISIBLE (-3275 3375);
FORCEPROP 1 LAST BODY_TYPE PLUMBING
J 0
(-3275 3425);
DISPLAY 0.872340 (-3275 3425);
PAINT GREEN (-3275 3425);
DISPLAY INVISIBLE (-3275 3425);
FORCEPROP 1 LAST HDL_TAP TRUE
J 0
(-2950 3250);
DISPLAY 0.872340 (-2950 3250);
DISPLAY INVISIBLE (-2950 3250);
FORCEPROP 1 LAST PATH I208
J 0
(-3277 3375);
DISPLAY 0.872340 (-3277 3375);
PAINT GREEN (-3277 3375);
DISPLAY INVISIBLE (-3277 3375);
FORCEADD TAP..1
(-3275 3425);
FORCEPROP 3 LASTPIN (-3325 3425) SIG_NAME M_L_CPU1_SB_DQ<13>
J 0
(-3315 3435);
DISPLAY 0.659574 (-3315 3435);
PAINT MONO (-3315 3435);
DISPLAY INVISIBLE (-3315 3435);
FORCEPROP 1 LASTPIN (-3325 3425) BN 13
J 0
(-3337 3433);
DISPLAY 0.489362 (-3337 3433);
PAINT GREEN (-3337 3433);
FORCEPROP 2 LAST CDS_LIB mstr_standard
J 0
(-3275 3425);
DISPLAY 0.723404 (-3275 3425);
PAINT MONO (-3275 3425);
DISPLAY INVISIBLE (-3275 3425);
FORCEPROP 1 LAST BODY_TYPE PLUMBING
J 0
(-3275 3475);
DISPLAY 0.872340 (-3275 3475);
PAINT GREEN (-3275 3475);
DISPLAY INVISIBLE (-3275 3475);
FORCEPROP 1 LAST HDL_TAP TRUE
J 0
(-2950 3300);
DISPLAY 0.872340 (-2950 3300);
DISPLAY INVISIBLE (-2950 3300);
FORCEPROP 1 LAST PATH I209
J 0
(-3277 3425);
DISPLAY 0.872340 (-3277 3425);
PAINT GREEN (-3277 3425);
DISPLAY INVISIBLE (-3277 3425);
FORCEADD TAP..1
(-3275 3225);
FORCEPROP 3 LASTPIN (-3325 3225) SIG_NAME M_L_CPU1_SB_DQ<16>
J 0
(-3315 3235);
DISPLAY 0.659574 (-3315 3235);
PAINT MONO (-3315 3235);
DISPLAY INVISIBLE (-3315 3235);
FORCEPROP 1 LASTPIN (-3325 3225) BN 16
J 0
(-3337 3233);
DISPLAY 0.489362 (-3337 3233);
PAINT GREEN (-3337 3233);
FORCEPROP 2 LAST CDS_LIB mstr_standard
J 0
(-3275 3225);
DISPLAY 0.723404 (-3275 3225);
PAINT MONO (-3275 3225);
DISPLAY INVISIBLE (-3275 3225);
FORCEPROP 1 LAST BODY_TYPE PLUMBING
J 0
(-3275 3275);
DISPLAY 0.872340 (-3275 3275);
PAINT GREEN (-3275 3275);
DISPLAY INVISIBLE (-3275 3275);
FORCEPROP 1 LAST HDL_TAP TRUE
J 0
(-2950 3100);
DISPLAY 0.872340 (-2950 3100);
DISPLAY INVISIBLE (-2950 3100);
FORCEPROP 1 LAST PATH I210
J 0
(-3277 3225);
DISPLAY 0.872340 (-3277 3225);
PAINT GREEN (-3277 3225);
DISPLAY INVISIBLE (-3277 3225);
FORCEADD TAP..1
(-3275 3325);
FORCEPROP 3 LASTPIN (-3325 3325) SIG_NAME M_L_CPU1_SB_DQ<15>
J 0
(-3315 3335);
DISPLAY 0.659574 (-3315 3335);
PAINT MONO (-3315 3335);
DISPLAY INVISIBLE (-3315 3335);
FORCEPROP 1 LASTPIN (-3325 3325) BN 15
J 0
(-3337 3333);
DISPLAY 0.489362 (-3337 3333);
PAINT GREEN (-3337 3333);
FORCEPROP 2 LAST CDS_LIB mstr_standard
J 0
(-3275 3325);
DISPLAY 0.723404 (-3275 3325);
PAINT MONO (-3275 3325);
DISPLAY INVISIBLE (-3275 3325);
FORCEPROP 1 LAST BODY_TYPE PLUMBING
J 0
(-3275 3375);
DISPLAY 0.872340 (-3275 3375);
PAINT GREEN (-3275 3375);
DISPLAY INVISIBLE (-3275 3375);
FORCEPROP 1 LAST HDL_TAP TRUE
J 0
(-2950 3200);
DISPLAY 0.872340 (-2950 3200);
DISPLAY INVISIBLE (-2950 3200);
FORCEPROP 1 LAST PATH I211
J 0
(-3277 3325);
DISPLAY 0.872340 (-3277 3325);
PAINT GREEN (-3277 3325);
DISPLAY INVISIBLE (-3277 3325);
FORCEADD TAP..1
(-3275 3175);
FORCEPROP 3 LASTPIN (-3325 3175) SIG_NAME M_L_CPU1_SB_DQ<17>
J 0
(-3315 3185);
DISPLAY 0.659574 (-3315 3185);
PAINT MONO (-3315 3185);
DISPLAY INVISIBLE (-3315 3185);
FORCEPROP 1 LASTPIN (-3325 3175) BN 17
J 0
(-3337 3183);
DISPLAY 0.489362 (-3337 3183);
PAINT GREEN (-3337 3183);
FORCEPROP 2 LAST CDS_LIB mstr_standard
J 0
(-3275 3175);
DISPLAY 0.723404 (-3275 3175);
PAINT MONO (-3275 3175);
DISPLAY INVISIBLE (-3275 3175);
FORCEPROP 1 LAST BODY_TYPE PLUMBING
J 0
(-3275 3225);
DISPLAY 0.872340 (-3275 3225);
PAINT GREEN (-3275 3225);
DISPLAY INVISIBLE (-3275 3225);
FORCEPROP 1 LAST HDL_TAP TRUE
J 0
(-2950 3050);
DISPLAY 0.872340 (-2950 3050);
DISPLAY INVISIBLE (-2950 3050);
FORCEPROP 1 LAST PATH I212
J 0
(-3277 3175);
DISPLAY 0.872340 (-3277 3175);
PAINT GREEN (-3277 3175);
DISPLAY INVISIBLE (-3277 3175);
FORCEADD TAP..1
(-3275 3125);
FORCEPROP 3 LASTPIN (-3325 3125) SIG_NAME M_L_CPU1_SB_DQ<18>
J 0
(-3315 3135);
DISPLAY 0.659574 (-3315 3135);
PAINT MONO (-3315 3135);
DISPLAY INVISIBLE (-3315 3135);
FORCEPROP 1 LASTPIN (-3325 3125) BN 18
J 0
(-3337 3133);
DISPLAY 0.489362 (-3337 3133);
PAINT GREEN (-3337 3133);
FORCEPROP 2 LAST CDS_LIB mstr_standard
J 0
(-3275 3125);
DISPLAY 0.723404 (-3275 3125);
PAINT MONO (-3275 3125);
DISPLAY INVISIBLE (-3275 3125);
FORCEPROP 1 LAST BODY_TYPE PLUMBING
J 0
(-3275 3175);
DISPLAY 0.872340 (-3275 3175);
PAINT GREEN (-3275 3175);
DISPLAY INVISIBLE (-3275 3175);
FORCEPROP 1 LAST HDL_TAP TRUE
J 0
(-2950 3000);
DISPLAY 0.872340 (-2950 3000);
DISPLAY INVISIBLE (-2950 3000);
FORCEPROP 1 LAST PATH I213
J 0
(-3277 3125);
DISPLAY 0.872340 (-3277 3125);
PAINT GREEN (-3277 3125);
DISPLAY INVISIBLE (-3277 3125);
FORCEADD TAP..1
(-3275 3075);
FORCEPROP 3 LASTPIN (-3325 3075) SIG_NAME M_L_CPU1_SB_DQ<19>
J 0
(-3315 3085);
DISPLAY 0.659574 (-3315 3085);
PAINT MONO (-3315 3085);
DISPLAY INVISIBLE (-3315 3085);
FORCEPROP 1 LASTPIN (-3325 3075) BN 19
J 0
(-3337 3083);
DISPLAY 0.489362 (-3337 3083);
PAINT GREEN (-3337 3083);
FORCEPROP 2 LAST CDS_LIB mstr_standard
J 0
(-3275 3075);
DISPLAY 0.723404 (-3275 3075);
PAINT MONO (-3275 3075);
DISPLAY INVISIBLE (-3275 3075);
FORCEPROP 1 LAST BODY_TYPE PLUMBING
J 0
(-3275 3125);
DISPLAY 0.872340 (-3275 3125);
PAINT GREEN (-3275 3125);
DISPLAY INVISIBLE (-3275 3125);
FORCEPROP 1 LAST HDL_TAP TRUE
J 0
(-2950 2950);
DISPLAY 0.872340 (-2950 2950);
DISPLAY INVISIBLE (-2950 2950);
FORCEPROP 1 LAST PATH I214
J 0
(-3277 3075);
DISPLAY 0.872340 (-3277 3075);
PAINT GREEN (-3277 3075);
DISPLAY INVISIBLE (-3277 3075);
FORCEADD TAP..1
(-3275 2975);
FORCEPROP 3 LASTPIN (-3325 2975) SIG_NAME M_L_CPU1_SB_DQ<21>
J 0
(-3315 2985);
DISPLAY 0.659574 (-3315 2985);
PAINT MONO (-3315 2985);
DISPLAY INVISIBLE (-3315 2985);
FORCEPROP 1 LASTPIN (-3325 2975) BN 21
J 0
(-3337 2983);
DISPLAY 0.489362 (-3337 2983);
PAINT GREEN (-3337 2983);
FORCEPROP 2 LAST CDS_LIB mstr_standard
J 0
(-3275 2975);
DISPLAY 0.723404 (-3275 2975);
PAINT MONO (-3275 2975);
DISPLAY INVISIBLE (-3275 2975);
FORCEPROP 1 LAST BODY_TYPE PLUMBING
J 0
(-3275 3025);
DISPLAY 0.872340 (-3275 3025);
PAINT GREEN (-3275 3025);
DISPLAY INVISIBLE (-3275 3025);
FORCEPROP 1 LAST HDL_TAP TRUE
J 0
(-2950 2850);
DISPLAY 0.872340 (-2950 2850);
DISPLAY INVISIBLE (-2950 2850);
FORCEPROP 1 LAST PATH I215
J 0
(-3277 2975);
DISPLAY 0.872340 (-3277 2975);
PAINT GREEN (-3277 2975);
DISPLAY INVISIBLE (-3277 2975);
FORCEADD TAP..1
(-3275 3025);
FORCEPROP 3 LASTPIN (-3325 3025) SIG_NAME M_L_CPU1_SB_DQ<20>
J 0
(-3315 3035);
DISPLAY 0.659574 (-3315 3035);
PAINT MONO (-3315 3035);
DISPLAY INVISIBLE (-3315 3035);
FORCEPROP 1 LASTPIN (-3325 3025) BN 20
J 0
(-3337 3033);
DISPLAY 0.489362 (-3337 3033);
PAINT GREEN (-3337 3033);
FORCEPROP 2 LAST CDS_LIB mstr_standard
J 0
(-3275 3025);
DISPLAY 0.723404 (-3275 3025);
PAINT MONO (-3275 3025);
DISPLAY INVISIBLE (-3275 3025);
FORCEPROP 1 LAST BODY_TYPE PLUMBING
J 0
(-3275 3075);
DISPLAY 0.872340 (-3275 3075);
PAINT GREEN (-3275 3075);
DISPLAY INVISIBLE (-3275 3075);
FORCEPROP 1 LAST HDL_TAP TRUE
J 0
(-2950 2900);
DISPLAY 0.872340 (-2950 2900);
DISPLAY INVISIBLE (-2950 2900);
FORCEPROP 1 LAST PATH I216
J 0
(-3277 3025);
DISPLAY 0.872340 (-3277 3025);
PAINT GREEN (-3277 3025);
DISPLAY INVISIBLE (-3277 3025);
FORCEADD TAP..1
(-3275 2925);
FORCEPROP 3 LASTPIN (-3325 2925) SIG_NAME M_L_CPU1_SB_DQ<22>
J 0
(-3315 2935);
DISPLAY 0.659574 (-3315 2935);
PAINT MONO (-3315 2935);
DISPLAY INVISIBLE (-3315 2935);
FORCEPROP 1 LASTPIN (-3325 2925) BN 22
J 0
(-3337 2933);
DISPLAY 0.489362 (-3337 2933);
PAINT GREEN (-3337 2933);
FORCEPROP 2 LAST CDS_LIB mstr_standard
J 0
(-3275 2925);
DISPLAY 0.723404 (-3275 2925);
PAINT MONO (-3275 2925);
DISPLAY INVISIBLE (-3275 2925);
FORCEPROP 1 LAST BODY_TYPE PLUMBING
J 0
(-3275 2975);
DISPLAY 0.872340 (-3275 2975);
PAINT GREEN (-3275 2975);
DISPLAY INVISIBLE (-3275 2975);
FORCEPROP 1 LAST HDL_TAP TRUE
J 0
(-2950 2800);
DISPLAY 0.872340 (-2950 2800);
DISPLAY INVISIBLE (-2950 2800);
FORCEPROP 1 LAST PATH I217
J 0
(-3277 2925);
DISPLAY 0.872340 (-3277 2925);
PAINT GREEN (-3277 2925);
DISPLAY INVISIBLE (-3277 2925);
FORCEADD TAP..1
(-3275 2875);
FORCEPROP 3 LASTPIN (-3325 2875) SIG_NAME M_L_CPU1_SB_DQ<23>
J 0
(-3315 2885);
DISPLAY 0.659574 (-3315 2885);
PAINT MONO (-3315 2885);
DISPLAY INVISIBLE (-3315 2885);
FORCEPROP 1 LASTPIN (-3325 2875) BN 23
J 0
(-3337 2883);
DISPLAY 0.489362 (-3337 2883);
PAINT GREEN (-3337 2883);
FORCEPROP 2 LAST CDS_LIB mstr_standard
J 0
(-3275 2875);
DISPLAY 0.723404 (-3275 2875);
PAINT MONO (-3275 2875);
DISPLAY INVISIBLE (-3275 2875);
FORCEPROP 1 LAST BODY_TYPE PLUMBING
J 0
(-3275 2925);
DISPLAY 0.872340 (-3275 2925);
PAINT GREEN (-3275 2925);
DISPLAY INVISIBLE (-3275 2925);
FORCEPROP 1 LAST HDL_TAP TRUE
J 0
(-2950 2750);
DISPLAY 0.872340 (-2950 2750);
DISPLAY INVISIBLE (-2950 2750);
FORCEPROP 1 LAST PATH I218
J 0
(-3277 2875);
DISPLAY 0.872340 (-3277 2875);
PAINT GREEN (-3277 2875);
DISPLAY INVISIBLE (-3277 2875);
FORCEADD TAP..1
(-3275 2725);
FORCEPROP 3 LASTPIN (-3325 2725) SIG_NAME M_L_CPU1_SB_DQ<25>
J 0
(-3315 2735);
DISPLAY 0.659574 (-3315 2735);
PAINT MONO (-3315 2735);
DISPLAY INVISIBLE (-3315 2735);
FORCEPROP 1 LASTPIN (-3325 2725) BN 25
J 0
(-3337 2733);
DISPLAY 0.489362 (-3337 2733);
PAINT GREEN (-3337 2733);
FORCEPROP 2 LAST CDS_LIB mstr_standard
J 0
(-3275 2725);
DISPLAY 0.723404 (-3275 2725);
PAINT MONO (-3275 2725);
DISPLAY INVISIBLE (-3275 2725);
FORCEPROP 1 LAST BODY_TYPE PLUMBING
J 0
(-3275 2775);
DISPLAY 0.872340 (-3275 2775);
PAINT GREEN (-3275 2775);
DISPLAY INVISIBLE (-3275 2775);
FORCEPROP 1 LAST HDL_TAP TRUE
J 0
(-2950 2600);
DISPLAY 0.872340 (-2950 2600);
DISPLAY INVISIBLE (-2950 2600);
FORCEPROP 1 LAST PATH I219
J 0
(-3277 2725);
DISPLAY 0.872340 (-3277 2725);
PAINT GREEN (-3277 2725);
DISPLAY INVISIBLE (-3277 2725);
FORCEADD TAP..1
(-3275 2775);
FORCEPROP 3 LASTPIN (-3325 2775) SIG_NAME M_L_CPU1_SB_DQ<24>
J 0
(-3315 2785);
DISPLAY 0.659574 (-3315 2785);
PAINT MONO (-3315 2785);
DISPLAY INVISIBLE (-3315 2785);
FORCEPROP 1 LASTPIN (-3325 2775) BN 24
J 0
(-3337 2783);
DISPLAY 0.489362 (-3337 2783);
PAINT GREEN (-3337 2783);
FORCEPROP 2 LAST CDS_LIB mstr_standard
J 0
(-3275 2775);
DISPLAY 0.723404 (-3275 2775);
PAINT MONO (-3275 2775);
DISPLAY INVISIBLE (-3275 2775);
FORCEPROP 1 LAST BODY_TYPE PLUMBING
J 0
(-3275 2825);
DISPLAY 0.872340 (-3275 2825);
PAINT GREEN (-3275 2825);
DISPLAY INVISIBLE (-3275 2825);
FORCEPROP 1 LAST HDL_TAP TRUE
J 0
(-2950 2650);
DISPLAY 0.872340 (-2950 2650);
DISPLAY INVISIBLE (-2950 2650);
FORCEPROP 1 LAST PATH I220
J 0
(-3277 2775);
DISPLAY 0.872340 (-3277 2775);
PAINT GREEN (-3277 2775);
DISPLAY INVISIBLE (-3277 2775);
FORCEADD TAP..1
(-3275 2675);
FORCEPROP 3 LASTPIN (-3325 2675) SIG_NAME M_L_CPU1_SB_DQ<26>
J 0
(-3315 2685);
DISPLAY 0.659574 (-3315 2685);
PAINT MONO (-3315 2685);
DISPLAY INVISIBLE (-3315 2685);
FORCEPROP 1 LASTPIN (-3325 2675) BN 26
J 0
(-3337 2683);
DISPLAY 0.489362 (-3337 2683);
PAINT GREEN (-3337 2683);
FORCEPROP 2 LAST CDS_LIB mstr_standard
J 0
(-3275 2675);
DISPLAY 0.723404 (-3275 2675);
PAINT MONO (-3275 2675);
DISPLAY INVISIBLE (-3275 2675);
FORCEPROP 1 LAST BODY_TYPE PLUMBING
J 0
(-3275 2725);
DISPLAY 0.872340 (-3275 2725);
PAINT GREEN (-3275 2725);
DISPLAY INVISIBLE (-3275 2725);
FORCEPROP 1 LAST HDL_TAP TRUE
J 0
(-2950 2550);
DISPLAY 0.872340 (-2950 2550);
DISPLAY INVISIBLE (-2950 2550);
FORCEPROP 1 LAST PATH I221
J 0
(-3277 2675);
DISPLAY 0.872340 (-3277 2675);
PAINT GREEN (-3277 2675);
DISPLAY INVISIBLE (-3277 2675);
FORCEADD TAP..1
(-3275 2625);
FORCEPROP 3 LASTPIN (-3325 2625) SIG_NAME M_L_CPU1_SB_DQ<27>
J 0
(-3315 2635);
DISPLAY 0.659574 (-3315 2635);
PAINT MONO (-3315 2635);
DISPLAY INVISIBLE (-3315 2635);
FORCEPROP 1 LASTPIN (-3325 2625) BN 27
J 0
(-3337 2633);
DISPLAY 0.489362 (-3337 2633);
PAINT GREEN (-3337 2633);
FORCEPROP 2 LAST CDS_LIB mstr_standard
J 0
(-3275 2625);
DISPLAY 0.723404 (-3275 2625);
PAINT MONO (-3275 2625);
DISPLAY INVISIBLE (-3275 2625);
FORCEPROP 1 LAST BODY_TYPE PLUMBING
J 0
(-3275 2675);
DISPLAY 0.872340 (-3275 2675);
PAINT GREEN (-3275 2675);
DISPLAY INVISIBLE (-3275 2675);
FORCEPROP 1 LAST HDL_TAP TRUE
J 0
(-2950 2500);
DISPLAY 0.872340 (-2950 2500);
DISPLAY INVISIBLE (-2950 2500);
FORCEPROP 1 LAST PATH I222
J 0
(-3277 2625);
DISPLAY 0.872340 (-3277 2625);
PAINT GREEN (-3277 2625);
DISPLAY INVISIBLE (-3277 2625);
FORCEADD TAP..1
(-3275 2575);
FORCEPROP 3 LASTPIN (-3325 2575) SIG_NAME M_L_CPU1_SB_DQ<28>
J 0
(-3315 2585);
DISPLAY 0.659574 (-3315 2585);
PAINT MONO (-3315 2585);
DISPLAY INVISIBLE (-3315 2585);
FORCEPROP 1 LASTPIN (-3325 2575) BN 28
J 0
(-3337 2583);
DISPLAY 0.489362 (-3337 2583);
PAINT GREEN (-3337 2583);
FORCEPROP 2 LAST CDS_LIB mstr_standard
J 0
(-3275 2575);
DISPLAY 0.723404 (-3275 2575);
PAINT MONO (-3275 2575);
DISPLAY INVISIBLE (-3275 2575);
FORCEPROP 1 LAST BODY_TYPE PLUMBING
J 0
(-3275 2625);
DISPLAY 0.872340 (-3275 2625);
PAINT GREEN (-3275 2625);
DISPLAY INVISIBLE (-3275 2625);
FORCEPROP 1 LAST HDL_TAP TRUE
J 0
(-2950 2450);
DISPLAY 0.872340 (-2950 2450);
DISPLAY INVISIBLE (-2950 2450);
FORCEPROP 1 LAST PATH I223
J 0
(-3277 2575);
DISPLAY 0.872340 (-3277 2575);
PAINT GREEN (-3277 2575);
DISPLAY INVISIBLE (-3277 2575);
FORCEADD TAP..1
(-3275 2475);
FORCEPROP 3 LASTPIN (-3325 2475) SIG_NAME M_L_CPU1_SB_DQ<30>
J 0
(-3315 2485);
DISPLAY 0.659574 (-3315 2485);
PAINT MONO (-3315 2485);
DISPLAY INVISIBLE (-3315 2485);
FORCEPROP 1 LASTPIN (-3325 2475) BN 30
J 0
(-3337 2483);
DISPLAY 0.489362 (-3337 2483);
PAINT GREEN (-3337 2483);
FORCEPROP 2 LAST CDS_LIB mstr_standard
J 0
(-3275 2475);
DISPLAY 0.723404 (-3275 2475);
PAINT MONO (-3275 2475);
DISPLAY INVISIBLE (-3275 2475);
FORCEPROP 1 LAST BODY_TYPE PLUMBING
J 0
(-3275 2525);
DISPLAY 0.872340 (-3275 2525);
PAINT GREEN (-3275 2525);
DISPLAY INVISIBLE (-3275 2525);
FORCEPROP 1 LAST HDL_TAP TRUE
J 0
(-2950 2350);
DISPLAY 0.872340 (-2950 2350);
DISPLAY INVISIBLE (-2950 2350);
FORCEPROP 1 LAST PATH I224
J 0
(-3277 2475);
DISPLAY 0.872340 (-3277 2475);
PAINT GREEN (-3277 2475);
DISPLAY INVISIBLE (-3277 2475);
FORCEADD TAP..1
(-3275 2525);
FORCEPROP 3 LASTPIN (-3325 2525) SIG_NAME M_L_CPU1_SB_DQ<29>
J 0
(-3315 2535);
DISPLAY 0.659574 (-3315 2535);
PAINT MONO (-3315 2535);
DISPLAY INVISIBLE (-3315 2535);
FORCEPROP 1 LASTPIN (-3325 2525) BN 29
J 0
(-3337 2533);
DISPLAY 0.489362 (-3337 2533);
PAINT GREEN (-3337 2533);
FORCEPROP 2 LAST CDS_LIB mstr_standard
J 0
(-3275 2525);
DISPLAY 0.723404 (-3275 2525);
PAINT MONO (-3275 2525);
DISPLAY INVISIBLE (-3275 2525);
FORCEPROP 1 LAST BODY_TYPE PLUMBING
J 0
(-3275 2575);
DISPLAY 0.872340 (-3275 2575);
PAINT GREEN (-3275 2575);
DISPLAY INVISIBLE (-3275 2575);
FORCEPROP 1 LAST HDL_TAP TRUE
J 0
(-2950 2400);
DISPLAY 0.872340 (-2950 2400);
DISPLAY INVISIBLE (-2950 2400);
FORCEPROP 1 LAST PATH I225
J 0
(-3277 2525);
DISPLAY 0.872340 (-3277 2525);
PAINT GREEN (-3277 2525);
DISPLAY INVISIBLE (-3277 2525);
FORCEADD TAP..1
(-3275 2425);
FORCEPROP 3 LASTPIN (-3325 2425) SIG_NAME M_L_CPU1_SB_DQ<31>
J 0
(-3315 2435);
DISPLAY 0.659574 (-3315 2435);
PAINT MONO (-3315 2435);
DISPLAY INVISIBLE (-3315 2435);
FORCEPROP 1 LASTPIN (-3325 2425) BN 31
J 0
(-3337 2433);
DISPLAY 0.489362 (-3337 2433);
PAINT GREEN (-3337 2433);
FORCEPROP 2 LAST CDS_LIB mstr_standard
J 0
(-3275 2425);
DISPLAY 0.723404 (-3275 2425);
PAINT MONO (-3275 2425);
DISPLAY INVISIBLE (-3275 2425);
FORCEPROP 1 LAST BODY_TYPE PLUMBING
J 0
(-3275 2475);
DISPLAY 0.872340 (-3275 2475);
PAINT GREEN (-3275 2475);
DISPLAY INVISIBLE (-3275 2475);
FORCEPROP 1 LAST HDL_TAP TRUE
J 0
(-2950 2300);
DISPLAY 0.872340 (-2950 2300);
DISPLAY INVISIBLE (-2950 2300);
FORCEPROP 1 LAST PATH I226
J 0
(-3277 2425);
DISPLAY 0.872340 (-3277 2425);
PAINT GREEN (-3277 2425);
DISPLAY INVISIBLE (-3277 2425);
FORCEADD TAP..1
(-3275 2325);
FORCEPROP 3 LASTPIN (-3325 2325) SIG_NAME M_L_CPU1_SA_CB<0>
J 0
(-3315 2335);
DISPLAY 0.659574 (-3315 2335);
PAINT MONO (-3315 2335);
DISPLAY INVISIBLE (-3315 2335);
FORCEPROP 1 LASTPIN (-3325 2325) BN 0
J 0
(-3337 2333);
DISPLAY 0.489362 (-3337 2333);
PAINT GREEN (-3337 2333);
FORCEPROP 2 LAST CDS_LIB mstr_standard
J 2
(-3275 2325);
DISPLAY 0.723404 (-3275 2325);
PAINT MONO (-3275 2325);
DISPLAY INVISIBLE (-3275 2325);
FORCEPROP 1 LAST BODY_TYPE PLUMBING
J 0
(-3275 2375);
DISPLAY 0.872340 (-3275 2375);
PAINT GREEN (-3275 2375);
DISPLAY INVISIBLE (-3275 2375);
FORCEPROP 1 LAST HDL_TAP TRUE
J 0
(-2950 2200);
DISPLAY 0.872340 (-2950 2200);
DISPLAY INVISIBLE (-2950 2200);
FORCEPROP 1 LAST PATH I227
J 0
(-3277 2325);
DISPLAY 0.872340 (-3277 2325);
PAINT GREEN (-3277 2325);
DISPLAY INVISIBLE (-3277 2325);
FORCEADD TAP..1
(-3275 2275);
FORCEPROP 3 LASTPIN (-3325 2275) SIG_NAME M_L_CPU1_SA_CB<1>
J 0
(-3315 2285);
DISPLAY 0.659574 (-3315 2285);
PAINT MONO (-3315 2285);
DISPLAY INVISIBLE (-3315 2285);
FORCEPROP 1 LASTPIN (-3325 2275) BN 1
J 0
(-3337 2283);
DISPLAY 0.489362 (-3337 2283);
PAINT GREEN (-3337 2283);
FORCEPROP 2 LAST CDS_LIB mstr_standard
J 2
(-3275 2275);
DISPLAY 0.723404 (-3275 2275);
PAINT MONO (-3275 2275);
DISPLAY INVISIBLE (-3275 2275);
FORCEPROP 1 LAST BODY_TYPE PLUMBING
J 0
(-3275 2325);
DISPLAY 0.872340 (-3275 2325);
PAINT GREEN (-3275 2325);
DISPLAY INVISIBLE (-3275 2325);
FORCEPROP 1 LAST HDL_TAP TRUE
J 0
(-2950 2150);
DISPLAY 0.872340 (-2950 2150);
DISPLAY INVISIBLE (-2950 2150);
FORCEPROP 1 LAST PATH I228
J 0
(-3277 2275);
DISPLAY 0.872340 (-3277 2275);
PAINT GREEN (-3277 2275);
DISPLAY INVISIBLE (-3277 2275);
FORCEADD TAP..1
(-3275 2225);
FORCEPROP 3 LASTPIN (-3325 2225) SIG_NAME M_L_CPU1_SA_CB<2>
J 0
(-3315 2235);
DISPLAY 0.659574 (-3315 2235);
PAINT MONO (-3315 2235);
DISPLAY INVISIBLE (-3315 2235);
FORCEPROP 1 LASTPIN (-3325 2225) BN 2
J 0
(-3337 2233);
DISPLAY 0.489362 (-3337 2233);
PAINT GREEN (-3337 2233);
FORCEPROP 2 LAST CDS_LIB mstr_standard
J 2
(-3275 2225);
DISPLAY 0.723404 (-3275 2225);
PAINT MONO (-3275 2225);
DISPLAY INVISIBLE (-3275 2225);
FORCEPROP 1 LAST BODY_TYPE PLUMBING
J 0
(-3275 2275);
DISPLAY 0.872340 (-3275 2275);
PAINT GREEN (-3275 2275);
DISPLAY INVISIBLE (-3275 2275);
FORCEPROP 1 LAST HDL_TAP TRUE
J 0
(-2950 2100);
DISPLAY 0.872340 (-2950 2100);
DISPLAY INVISIBLE (-2950 2100);
FORCEPROP 1 LAST PATH I229
J 0
(-3277 2225);
DISPLAY 0.872340 (-3277 2225);
PAINT GREEN (-3277 2225);
DISPLAY INVISIBLE (-3277 2225);
FORCEADD TAP..1
(-3275 2175);
FORCEPROP 3 LASTPIN (-3325 2175) SIG_NAME M_L_CPU1_SA_CB<3>
J 0
(-3315 2185);
DISPLAY 0.659574 (-3315 2185);
PAINT MONO (-3315 2185);
DISPLAY INVISIBLE (-3315 2185);
FORCEPROP 1 LASTPIN (-3325 2175) BN 3
J 0
(-3337 2183);
DISPLAY 0.489362 (-3337 2183);
PAINT GREEN (-3337 2183);
FORCEPROP 2 LAST CDS_LIB mstr_standard
J 2
(-3275 2175);
DISPLAY 0.723404 (-3275 2175);
PAINT MONO (-3275 2175);
DISPLAY INVISIBLE (-3275 2175);
FORCEPROP 1 LAST BODY_TYPE PLUMBING
J 0
(-3275 2225);
DISPLAY 0.872340 (-3275 2225);
PAINT GREEN (-3275 2225);
DISPLAY INVISIBLE (-3275 2225);
FORCEPROP 1 LAST HDL_TAP TRUE
J 0
(-2950 2050);
DISPLAY 0.872340 (-2950 2050);
DISPLAY INVISIBLE (-2950 2050);
FORCEPROP 1 LAST PATH I230
J 0
(-3277 2175);
DISPLAY 0.872340 (-3277 2175);
PAINT GREEN (-3277 2175);
DISPLAY INVISIBLE (-3277 2175);
FORCEADD TAP..1
(-3275 2125);
FORCEPROP 3 LASTPIN (-3325 2125) SIG_NAME M_L_CPU1_SA_CB<4>
J 0
(-3315 2135);
DISPLAY 0.659574 (-3315 2135);
PAINT MONO (-3315 2135);
DISPLAY INVISIBLE (-3315 2135);
FORCEPROP 1 LASTPIN (-3325 2125) BN 4
J 0
(-3337 2133);
DISPLAY 0.489362 (-3337 2133);
PAINT GREEN (-3337 2133);
FORCEPROP 2 LAST CDS_LIB mstr_standard
J 2
(-3275 2125);
DISPLAY 0.723404 (-3275 2125);
PAINT MONO (-3275 2125);
DISPLAY INVISIBLE (-3275 2125);
FORCEPROP 1 LAST BODY_TYPE PLUMBING
J 0
(-3275 2175);
DISPLAY 0.872340 (-3275 2175);
PAINT GREEN (-3275 2175);
DISPLAY INVISIBLE (-3275 2175);
FORCEPROP 1 LAST HDL_TAP TRUE
J 0
(-2950 2000);
DISPLAY 0.872340 (-2950 2000);
DISPLAY INVISIBLE (-2950 2000);
FORCEPROP 1 LAST PATH I231
J 0
(-3277 2125);
DISPLAY 0.872340 (-3277 2125);
PAINT GREEN (-3277 2125);
DISPLAY INVISIBLE (-3277 2125);
FORCEADD TAP..1
(-3275 2075);
FORCEPROP 3 LASTPIN (-3325 2075) SIG_NAME M_L_CPU1_SA_CB<5>
J 0
(-3315 2085);
DISPLAY 0.659574 (-3315 2085);
PAINT MONO (-3315 2085);
DISPLAY INVISIBLE (-3315 2085);
FORCEPROP 1 LASTPIN (-3325 2075) BN 5
J 0
(-3337 2083);
DISPLAY 0.489362 (-3337 2083);
PAINT GREEN (-3337 2083);
FORCEPROP 2 LAST CDS_LIB mstr_standard
J 2
(-3275 2075);
DISPLAY 0.723404 (-3275 2075);
PAINT MONO (-3275 2075);
DISPLAY INVISIBLE (-3275 2075);
FORCEPROP 1 LAST BODY_TYPE PLUMBING
J 0
(-3275 2125);
DISPLAY 0.872340 (-3275 2125);
PAINT GREEN (-3275 2125);
DISPLAY INVISIBLE (-3275 2125);
FORCEPROP 1 LAST HDL_TAP TRUE
J 0
(-2950 1950);
DISPLAY 0.872340 (-2950 1950);
DISPLAY INVISIBLE (-2950 1950);
FORCEPROP 1 LAST PATH I232
J 0
(-3277 2075);
DISPLAY 0.872340 (-3277 2075);
PAINT GREEN (-3277 2075);
DISPLAY INVISIBLE (-3277 2075);
FORCEADD OFFPAGE..6
R 2
(-2675 1925);
FORCEPROP 2 LAST $XR0 108 
J 0
(-2461 1925);
DISPLAY 0.638298 (-2461 1925);
PAINT MONO (-2461 1925);
FORCEPROP 2 LAST PATH I233
J 0
(-2450 1975);
DISPLAY 1.021277 (-2450 1975);
DISPLAY INVISIBLE (-2450 1975);
FORCEPROP 1 LAST COMMENT_BODY TRUE
J 2
(-2775 1850);
DISPLAY 0.872340 (-2775 1850);
PAINT GREEN (-2775 1850);
DISPLAY INVISIBLE (-2775 1850);
FORCEPROP 1 LAST OFFPAGE TRUE
J 2
(-3000 1800);
DISPLAY 0.872340 (-3000 1800);
PAINT GREEN (-3000 1800);
DISPLAY INVISIBLE (-3000 1800);
FORCEPROP 2 LAST CDS_LIB mstr_standard
J 2
(-2675 1925);
DISPLAY 0.723404 (-2675 1925);
PAINT MONO (-2675 1925);
DISPLAY INVISIBLE (-2675 1925);
FORCEADD TAP..1
(-3275 2025);
FORCEPROP 3 LASTPIN (-3325 2025) SIG_NAME M_L_CPU1_SA_CB<6>
J 0
(-3315 2035);
DISPLAY 0.659574 (-3315 2035);
PAINT MONO (-3315 2035);
DISPLAY INVISIBLE (-3315 2035);
FORCEPROP 1 LASTPIN (-3325 2025) BN 6
J 0
(-3337 2033);
DISPLAY 0.489362 (-3337 2033);
PAINT GREEN (-3337 2033);
FORCEPROP 2 LAST CDS_LIB mstr_standard
J 2
(-3275 2025);
DISPLAY 0.723404 (-3275 2025);
PAINT MONO (-3275 2025);
DISPLAY INVISIBLE (-3275 2025);
FORCEPROP 1 LAST BODY_TYPE PLUMBING
J 0
(-3275 2075);
DISPLAY 0.872340 (-3275 2075);
PAINT GREEN (-3275 2075);
DISPLAY INVISIBLE (-3275 2075);
FORCEPROP 1 LAST HDL_TAP TRUE
J 0
(-2950 1900);
DISPLAY 0.872340 (-2950 1900);
DISPLAY INVISIBLE (-2950 1900);
FORCEPROP 1 LAST PATH I234
J 0
(-3277 2025);
DISPLAY 0.872340 (-3277 2025);
PAINT GREEN (-3277 2025);
DISPLAY INVISIBLE (-3277 2025);
FORCEADD TAP..1
(-3275 1975);
FORCEPROP 3 LASTPIN (-3325 1975) SIG_NAME M_L_CPU1_SA_CB<7>
J 0
(-3315 1985);
DISPLAY 0.659574 (-3315 1985);
PAINT MONO (-3315 1985);
DISPLAY INVISIBLE (-3315 1985);
FORCEPROP 1 LASTPIN (-3325 1975) BN 7
J 0
(-3337 1983);
DISPLAY 0.489362 (-3337 1983);
PAINT GREEN (-3337 1983);
FORCEPROP 2 LAST CDS_LIB mstr_standard
J 2
(-3275 1975);
DISPLAY 0.723404 (-3275 1975);
PAINT MONO (-3275 1975);
DISPLAY INVISIBLE (-3275 1975);
FORCEPROP 1 LAST BODY_TYPE PLUMBING
J 0
(-3275 2025);
DISPLAY 0.872340 (-3275 2025);
PAINT GREEN (-3275 2025);
DISPLAY INVISIBLE (-3275 2025);
FORCEPROP 1 LAST HDL_TAP TRUE
J 0
(-2950 1850);
DISPLAY 0.872340 (-2950 1850);
DISPLAY INVISIBLE (-2950 1850);
FORCEPROP 1 LAST PATH I235
J 0
(-3277 1975);
DISPLAY 0.872340 (-3277 1975);
PAINT GREEN (-3277 1975);
DISPLAY INVISIBLE (-3277 1975);
FORCEADD TAP..1
(-3275 1875);
FORCEPROP 3 LASTPIN (-3325 1875) SIG_NAME M_L_CPU1_SB_CB<0>
J 0
(-3315 1885);
DISPLAY 0.659574 (-3315 1885);
PAINT MONO (-3315 1885);
DISPLAY INVISIBLE (-3315 1885);
FORCEPROP 1 LASTPIN (-3325 1875) BN 0
J 0
(-3337 1883);
DISPLAY 0.489362 (-3337 1883);
PAINT GREEN (-3337 1883);
FORCEPROP 2 LAST CDS_LIB mstr_standard
J 2
(-3275 1875);
DISPLAY 0.723404 (-3275 1875);
PAINT MONO (-3275 1875);
DISPLAY INVISIBLE (-3275 1875);
FORCEPROP 1 LAST BODY_TYPE PLUMBING
J 0
(-3275 1925);
DISPLAY 0.872340 (-3275 1925);
PAINT GREEN (-3275 1925);
DISPLAY INVISIBLE (-3275 1925);
FORCEPROP 1 LAST HDL_TAP TRUE
J 0
(-2950 1750);
DISPLAY 0.872340 (-2950 1750);
DISPLAY INVISIBLE (-2950 1750);
FORCEPROP 1 LAST PATH I236
J 0
(-3277 1875);
DISPLAY 0.872340 (-3277 1875);
PAINT GREEN (-3277 1875);
DISPLAY INVISIBLE (-3277 1875);
FORCEADD TAP..1
(-3275 1825);
FORCEPROP 3 LASTPIN (-3325 1825) SIG_NAME M_L_CPU1_SB_CB<1>
J 0
(-3315 1835);
DISPLAY 0.659574 (-3315 1835);
PAINT MONO (-3315 1835);
DISPLAY INVISIBLE (-3315 1835);
FORCEPROP 1 LASTPIN (-3325 1825) BN 1
J 0
(-3337 1833);
DISPLAY 0.489362 (-3337 1833);
PAINT GREEN (-3337 1833);
FORCEPROP 2 LAST CDS_LIB mstr_standard
J 2
(-3275 1825);
DISPLAY 0.723404 (-3275 1825);
PAINT MONO (-3275 1825);
DISPLAY INVISIBLE (-3275 1825);
FORCEPROP 1 LAST BODY_TYPE PLUMBING
J 0
(-3275 1875);
DISPLAY 0.872340 (-3275 1875);
PAINT GREEN (-3275 1875);
DISPLAY INVISIBLE (-3275 1875);
FORCEPROP 1 LAST HDL_TAP TRUE
J 0
(-2950 1700);
DISPLAY 0.872340 (-2950 1700);
DISPLAY INVISIBLE (-2950 1700);
FORCEPROP 1 LAST PATH I237
J 0
(-3277 1825);
DISPLAY 0.872340 (-3277 1825);
PAINT GREEN (-3277 1825);
DISPLAY INVISIBLE (-3277 1825);
FORCEADD TAP..1
(-3275 1775);
FORCEPROP 3 LASTPIN (-3325 1775) SIG_NAME M_L_CPU1_SB_CB<2>
J 0
(-3315 1785);
DISPLAY 0.659574 (-3315 1785);
PAINT MONO (-3315 1785);
DISPLAY INVISIBLE (-3315 1785);
FORCEPROP 1 LASTPIN (-3325 1775) BN 2
J 0
(-3337 1783);
DISPLAY 0.489362 (-3337 1783);
PAINT GREEN (-3337 1783);
FORCEPROP 2 LAST CDS_LIB mstr_standard
J 2
(-3275 1775);
DISPLAY 0.723404 (-3275 1775);
PAINT MONO (-3275 1775);
DISPLAY INVISIBLE (-3275 1775);
FORCEPROP 1 LAST BODY_TYPE PLUMBING
J 0
(-3275 1825);
DISPLAY 0.872340 (-3275 1825);
PAINT GREEN (-3275 1825);
DISPLAY INVISIBLE (-3275 1825);
FORCEPROP 1 LAST HDL_TAP TRUE
J 0
(-2950 1650);
DISPLAY 0.872340 (-2950 1650);
DISPLAY INVISIBLE (-2950 1650);
FORCEPROP 1 LAST PATH I238
J 0
(-3277 1775);
DISPLAY 0.872340 (-3277 1775);
PAINT GREEN (-3277 1775);
DISPLAY INVISIBLE (-3277 1775);
FORCEADD TAP..1
(-3275 1675);
FORCEPROP 3 LASTPIN (-3325 1675) SIG_NAME M_L_CPU1_SB_CB<4>
J 0
(-3315 1685);
DISPLAY 0.659574 (-3315 1685);
PAINT MONO (-3315 1685);
DISPLAY INVISIBLE (-3315 1685);
FORCEPROP 1 LASTPIN (-3325 1675) BN 4
J 0
(-3337 1683);
DISPLAY 0.489362 (-3337 1683);
PAINT GREEN (-3337 1683);
FORCEPROP 2 LAST CDS_LIB mstr_standard
J 2
(-3275 1675);
DISPLAY 0.723404 (-3275 1675);
PAINT MONO (-3275 1675);
DISPLAY INVISIBLE (-3275 1675);
FORCEPROP 1 LAST BODY_TYPE PLUMBING
J 0
(-3275 1725);
DISPLAY 0.872340 (-3275 1725);
PAINT GREEN (-3275 1725);
DISPLAY INVISIBLE (-3275 1725);
FORCEPROP 1 LAST HDL_TAP TRUE
J 0
(-2950 1550);
DISPLAY 0.872340 (-2950 1550);
DISPLAY INVISIBLE (-2950 1550);
FORCEPROP 1 LAST PATH I239
J 0
(-3277 1675);
DISPLAY 0.872340 (-3277 1675);
PAINT GREEN (-3277 1675);
DISPLAY INVISIBLE (-3277 1675);
FORCEADD TAP..1
(-3275 1725);
FORCEPROP 3 LASTPIN (-3325 1725) SIG_NAME M_L_CPU1_SB_CB<3>
J 0
(-3315 1735);
DISPLAY 0.659574 (-3315 1735);
PAINT MONO (-3315 1735);
DISPLAY INVISIBLE (-3315 1735);
FORCEPROP 1 LASTPIN (-3325 1725) BN 3
J 0
(-3337 1733);
DISPLAY 0.489362 (-3337 1733);
PAINT GREEN (-3337 1733);
FORCEPROP 2 LAST CDS_LIB mstr_standard
J 2
(-3275 1725);
DISPLAY 0.723404 (-3275 1725);
PAINT MONO (-3275 1725);
DISPLAY INVISIBLE (-3275 1725);
FORCEPROP 1 LAST BODY_TYPE PLUMBING
J 0
(-3275 1775);
DISPLAY 0.872340 (-3275 1775);
PAINT GREEN (-3275 1775);
DISPLAY INVISIBLE (-3275 1775);
FORCEPROP 1 LAST HDL_TAP TRUE
J 0
(-2950 1600);
DISPLAY 0.872340 (-2950 1600);
DISPLAY INVISIBLE (-2950 1600);
FORCEPROP 1 LAST PATH I240
J 0
(-3277 1725);
DISPLAY 0.872340 (-3277 1725);
PAINT GREEN (-3277 1725);
DISPLAY INVISIBLE (-3277 1725);
FORCEADD TAP..1
(-3275 1575);
FORCEPROP 3 LASTPIN (-3325 1575) SIG_NAME M_L_CPU1_SB_CB<6>
J 0
(-3315 1585);
DISPLAY 0.659574 (-3315 1585);
PAINT MONO (-3315 1585);
DISPLAY INVISIBLE (-3315 1585);
FORCEPROP 1 LASTPIN (-3325 1575) BN 6
J 0
(-3337 1583);
DISPLAY 0.489362 (-3337 1583);
PAINT GREEN (-3337 1583);
FORCEPROP 2 LAST CDS_LIB mstr_standard
J 2
(-3275 1575);
DISPLAY 0.723404 (-3275 1575);
PAINT MONO (-3275 1575);
DISPLAY INVISIBLE (-3275 1575);
FORCEPROP 1 LAST BODY_TYPE PLUMBING
J 0
(-3275 1625);
DISPLAY 0.872340 (-3275 1625);
PAINT GREEN (-3275 1625);
DISPLAY INVISIBLE (-3275 1625);
FORCEPROP 1 LAST HDL_TAP TRUE
J 0
(-2950 1450);
DISPLAY 0.872340 (-2950 1450);
DISPLAY INVISIBLE (-2950 1450);
FORCEPROP 1 LAST PATH I241
J 0
(-3277 1575);
DISPLAY 0.872340 (-3277 1575);
PAINT GREEN (-3277 1575);
DISPLAY INVISIBLE (-3277 1575);
FORCEADD TAP..1
(-3275 1625);
FORCEPROP 3 LASTPIN (-3325 1625) SIG_NAME M_L_CPU1_SB_CB<5>
J 0
(-3315 1635);
DISPLAY 0.659574 (-3315 1635);
PAINT MONO (-3315 1635);
DISPLAY INVISIBLE (-3315 1635);
FORCEPROP 1 LASTPIN (-3325 1625) BN 5
J 0
(-3337 1633);
DISPLAY 0.489362 (-3337 1633);
PAINT GREEN (-3337 1633);
FORCEPROP 2 LAST CDS_LIB mstr_standard
J 2
(-3275 1625);
DISPLAY 0.723404 (-3275 1625);
PAINT MONO (-3275 1625);
DISPLAY INVISIBLE (-3275 1625);
FORCEPROP 1 LAST BODY_TYPE PLUMBING
J 0
(-3275 1675);
DISPLAY 0.872340 (-3275 1675);
PAINT GREEN (-3275 1675);
DISPLAY INVISIBLE (-3275 1675);
FORCEPROP 1 LAST HDL_TAP TRUE
J 0
(-2950 1500);
DISPLAY 0.872340 (-2950 1500);
DISPLAY INVISIBLE (-2950 1500);
FORCEPROP 1 LAST PATH I242
J 0
(-3277 1625);
DISPLAY 0.872340 (-3277 1625);
PAINT GREEN (-3277 1625);
DISPLAY INVISIBLE (-3277 1625);
FORCEADD TAP..1
(-3275 1525);
FORCEPROP 3 LASTPIN (-3325 1525) SIG_NAME M_L_CPU1_SB_CB<7>
J 0
(-3315 1535);
DISPLAY 0.659574 (-3315 1535);
PAINT MONO (-3315 1535);
DISPLAY INVISIBLE (-3315 1535);
FORCEPROP 1 LASTPIN (-3325 1525) BN 7
J 0
(-3337 1533);
DISPLAY 0.489362 (-3337 1533);
PAINT GREEN (-3337 1533);
FORCEPROP 2 LAST CDS_LIB mstr_standard
J 2
(-3275 1525);
DISPLAY 0.723404 (-3275 1525);
PAINT MONO (-3275 1525);
DISPLAY INVISIBLE (-3275 1525);
FORCEPROP 1 LAST BODY_TYPE PLUMBING
J 0
(-3275 1575);
DISPLAY 0.872340 (-3275 1575);
PAINT GREEN (-3275 1575);
DISPLAY INVISIBLE (-3275 1575);
FORCEPROP 1 LAST HDL_TAP TRUE
J 0
(-2950 1400);
DISPLAY 0.872340 (-2950 1400);
DISPLAY INVISIBLE (-2950 1400);
FORCEPROP 1 LAST PATH I243
J 0
(-3277 1525);
DISPLAY 0.872340 (-3277 1525);
PAINT GREEN (-3277 1525);
DISPLAY INVISIBLE (-3277 1525);
FORCEADD TAP..1
R 2
(-5700 5925);
FORCEPROP 3 LASTPIN (-5650 5925) SIG_NAME M_L_CPU1_SA_DQS_DP<0>
J 0
(-5640 5935);
DISPLAY 0.659574 (-5640 5935);
PAINT MONO (-5640 5935);
DISPLAY INVISIBLE (-5640 5935);
FORCEPROP 1 LASTPIN (-5650 5925) BN 0
J 2
(-5638 5933);
DISPLAY 0.489362 (-5638 5933);
PAINT GREEN (-5638 5933);
FORCEPROP 2 LAST CDS_LIB mstr_standard
J 2
(-5700 5925);
DISPLAY 0.723404 (-5700 5925);
PAINT MONO (-5700 5925);
DISPLAY INVISIBLE (-5700 5925);
FORCEPROP 1 LAST BODY_TYPE PLUMBING
J 2
(-5700 5975);
DISPLAY 0.872340 (-5700 5975);
PAINT GREEN (-5700 5975);
DISPLAY INVISIBLE (-5700 5975);
FORCEPROP 1 LAST HDL_TAP TRUE
J 2
(-6025 5800);
DISPLAY 0.872340 (-6025 5800);
DISPLAY INVISIBLE (-6025 5800);
FORCEPROP 1 LAST PATH I244
J 2
(-5698 5925);
DISPLAY 0.872340 (-5698 5925);
PAINT GREEN (-5698 5925);
DISPLAY INVISIBLE (-5698 5925);
FORCEADD TAP..1
R 2
(-5700 5825);
FORCEPROP 3 LASTPIN (-5650 5825) SIG_NAME M_L_CPU1_SA_DQS_DP<1>
J 0
(-5640 5835);
DISPLAY 0.659574 (-5640 5835);
PAINT MONO (-5640 5835);
DISPLAY INVISIBLE (-5640 5835);
FORCEPROP 1 LASTPIN (-5650 5825) BN 1
J 2
(-5638 5833);
DISPLAY 0.489362 (-5638 5833);
PAINT GREEN (-5638 5833);
FORCEPROP 2 LAST CDS_LIB mstr_standard
J 2
(-5700 5825);
DISPLAY 0.723404 (-5700 5825);
PAINT MONO (-5700 5825);
DISPLAY INVISIBLE (-5700 5825);
FORCEPROP 1 LAST BODY_TYPE PLUMBING
J 2
(-5700 5875);
DISPLAY 0.872340 (-5700 5875);
PAINT GREEN (-5700 5875);
DISPLAY INVISIBLE (-5700 5875);
FORCEPROP 1 LAST HDL_TAP TRUE
J 2
(-6025 5700);
DISPLAY 0.872340 (-6025 5700);
DISPLAY INVISIBLE (-6025 5700);
FORCEPROP 1 LAST PATH I245
J 2
(-5698 5825);
DISPLAY 0.872340 (-5698 5825);
PAINT GREEN (-5698 5825);
DISPLAY INVISIBLE (-5698 5825);
FORCEADD TAP..1
R 2
(-5700 5625);
FORCEPROP 3 LASTPIN (-5650 5625) SIG_NAME M_L_CPU1_SA_DQS_DP<3>
J 0
(-5640 5635);
DISPLAY 0.659574 (-5640 5635);
PAINT MONO (-5640 5635);
DISPLAY INVISIBLE (-5640 5635);
FORCEPROP 1 LASTPIN (-5650 5625) BN 3
J 2
(-5638 5633);
DISPLAY 0.489362 (-5638 5633);
PAINT GREEN (-5638 5633);
FORCEPROP 2 LAST CDS_LIB mstr_standard
J 2
(-5700 5625);
DISPLAY 0.723404 (-5700 5625);
PAINT MONO (-5700 5625);
DISPLAY INVISIBLE (-5700 5625);
FORCEPROP 1 LAST BODY_TYPE PLUMBING
J 2
(-5700 5675);
DISPLAY 0.872340 (-5700 5675);
PAINT GREEN (-5700 5675);
DISPLAY INVISIBLE (-5700 5675);
FORCEPROP 1 LAST HDL_TAP TRUE
J 2
(-6025 5500);
DISPLAY 0.872340 (-6025 5500);
DISPLAY INVISIBLE (-6025 5500);
FORCEPROP 1 LAST PATH I246
J 2
(-5698 5625);
DISPLAY 0.872340 (-5698 5625);
PAINT GREEN (-5698 5625);
DISPLAY INVISIBLE (-5698 5625);
FORCEADD TAP..1
R 2
(-5700 5725);
FORCEPROP 3 LASTPIN (-5650 5725) SIG_NAME M_L_CPU1_SA_DQS_DP<2>
J 0
(-5640 5735);
DISPLAY 0.659574 (-5640 5735);
PAINT MONO (-5640 5735);
DISPLAY INVISIBLE (-5640 5735);
FORCEPROP 1 LASTPIN (-5650 5725) BN 2
J 2
(-5638 5733);
DISPLAY 0.489362 (-5638 5733);
PAINT GREEN (-5638 5733);
FORCEPROP 2 LAST CDS_LIB mstr_standard
J 2
(-5700 5725);
DISPLAY 0.723404 (-5700 5725);
PAINT MONO (-5700 5725);
DISPLAY INVISIBLE (-5700 5725);
FORCEPROP 1 LAST BODY_TYPE PLUMBING
J 2
(-5700 5775);
DISPLAY 0.872340 (-5700 5775);
PAINT GREEN (-5700 5775);
DISPLAY INVISIBLE (-5700 5775);
FORCEPROP 1 LAST HDL_TAP TRUE
J 2
(-6025 5600);
DISPLAY 0.872340 (-6025 5600);
DISPLAY INVISIBLE (-6025 5600);
FORCEPROP 1 LAST PATH I247
J 2
(-5698 5725);
DISPLAY 0.872340 (-5698 5725);
PAINT GREEN (-5698 5725);
DISPLAY INVISIBLE (-5698 5725);
FORCEADD TAP..1
R 2
(-5900 5775);
FORCEPROP 3 LASTPIN (-5850 5775) SIG_NAME M_L_CPU1_SA_DQS_DN<1>
J 0
(-5840 5785);
DISPLAY 0.659574 (-5840 5785);
PAINT MONO (-5840 5785);
DISPLAY INVISIBLE (-5840 5785);
FORCEPROP 1 LASTPIN (-5850 5775) BN 1
J 2
(-5838 5783);
DISPLAY 0.489362 (-5838 5783);
PAINT GREEN (-5838 5783);
FORCEPROP 2 LAST CDS_LIB mstr_standard
J 2
(-5900 5775);
DISPLAY 0.723404 (-5900 5775);
PAINT MONO (-5900 5775);
DISPLAY INVISIBLE (-5900 5775);
FORCEPROP 1 LAST BODY_TYPE PLUMBING
J 2
(-5900 5825);
DISPLAY 0.872340 (-5900 5825);
PAINT GREEN (-5900 5825);
DISPLAY INVISIBLE (-5900 5825);
FORCEPROP 1 LAST HDL_TAP TRUE
J 2
(-6225 5650);
DISPLAY 0.872340 (-6225 5650);
DISPLAY INVISIBLE (-6225 5650);
FORCEPROP 1 LAST PATH I248
J 2
(-5898 5775);
DISPLAY 0.872340 (-5898 5775);
PAINT GREEN (-5898 5775);
DISPLAY INVISIBLE (-5898 5775);
FORCEADD TAP..1
R 2
(-5900 5875);
FORCEPROP 3 LASTPIN (-5850 5875) SIG_NAME M_L_CPU1_SA_DQS_DN<0>
J 0
(-5840 5885);
DISPLAY 0.659574 (-5840 5885);
PAINT MONO (-5840 5885);
DISPLAY INVISIBLE (-5840 5885);
FORCEPROP 1 LASTPIN (-5850 5875) BN 0
J 2
(-5838 5883);
DISPLAY 0.489362 (-5838 5883);
PAINT GREEN (-5838 5883);
FORCEPROP 2 LAST CDS_LIB mstr_standard
J 2
(-5900 5875);
DISPLAY 0.723404 (-5900 5875);
PAINT MONO (-5900 5875);
DISPLAY INVISIBLE (-5900 5875);
FORCEPROP 1 LAST BODY_TYPE PLUMBING
J 2
(-5900 5925);
DISPLAY 0.872340 (-5900 5925);
PAINT GREEN (-5900 5925);
DISPLAY INVISIBLE (-5900 5925);
FORCEPROP 1 LAST HDL_TAP TRUE
J 2
(-6225 5750);
DISPLAY 0.872340 (-6225 5750);
DISPLAY INVISIBLE (-6225 5750);
FORCEPROP 1 LAST PATH I249
J 2
(-5898 5875);
DISPLAY 0.872340 (-5898 5875);
PAINT GREEN (-5898 5875);
DISPLAY INVISIBLE (-5898 5875);
FORCEADD TAP..1
R 2
(-5900 5675);
FORCEPROP 3 LASTPIN (-5850 5675) SIG_NAME M_L_CPU1_SA_DQS_DN<2>
J 0
(-5840 5685);
DISPLAY 0.659574 (-5840 5685);
PAINT MONO (-5840 5685);
DISPLAY INVISIBLE (-5840 5685);
FORCEPROP 1 LASTPIN (-5850 5675) BN 2
J 2
(-5838 5683);
DISPLAY 0.489362 (-5838 5683);
PAINT GREEN (-5838 5683);
FORCEPROP 2 LAST CDS_LIB mstr_standard
J 2
(-5900 5675);
DISPLAY 0.723404 (-5900 5675);
PAINT MONO (-5900 5675);
DISPLAY INVISIBLE (-5900 5675);
FORCEPROP 1 LAST BODY_TYPE PLUMBING
J 2
(-5900 5725);
DISPLAY 0.872340 (-5900 5725);
PAINT GREEN (-5900 5725);
DISPLAY INVISIBLE (-5900 5725);
FORCEPROP 1 LAST HDL_TAP TRUE
J 2
(-6225 5550);
DISPLAY 0.872340 (-6225 5550);
DISPLAY INVISIBLE (-6225 5550);
FORCEPROP 1 LAST PATH I250
J 2
(-5898 5675);
DISPLAY 0.872340 (-5898 5675);
PAINT GREEN (-5898 5675);
DISPLAY INVISIBLE (-5898 5675);
FORCEADD TAP..1
R 2
(-5700 5525);
FORCEPROP 3 LASTPIN (-5650 5525) SIG_NAME M_L_CPU1_SA_DQS_DP<4>
J 0
(-5640 5535);
DISPLAY 0.659574 (-5640 5535);
PAINT MONO (-5640 5535);
DISPLAY INVISIBLE (-5640 5535);
FORCEPROP 1 LASTPIN (-5650 5525) BN 4
J 2
(-5638 5533);
DISPLAY 0.489362 (-5638 5533);
PAINT GREEN (-5638 5533);
FORCEPROP 2 LAST CDS_LIB mstr_standard
J 2
(-5700 5525);
DISPLAY 0.723404 (-5700 5525);
PAINT MONO (-5700 5525);
DISPLAY INVISIBLE (-5700 5525);
FORCEPROP 1 LAST BODY_TYPE PLUMBING
J 2
(-5700 5575);
DISPLAY 0.872340 (-5700 5575);
PAINT GREEN (-5700 5575);
DISPLAY INVISIBLE (-5700 5575);
FORCEPROP 1 LAST HDL_TAP TRUE
J 2
(-6025 5400);
DISPLAY 0.872340 (-6025 5400);
DISPLAY INVISIBLE (-6025 5400);
FORCEPROP 1 LAST PATH I251
J 2
(-5698 5525);
DISPLAY 0.872340 (-5698 5525);
PAINT GREEN (-5698 5525);
DISPLAY INVISIBLE (-5698 5525);
FORCEADD TAP..1
R 2
(-5700 5425);
FORCEPROP 3 LASTPIN (-5650 5425) SIG_NAME M_L_CPU1_SA_DQS_DP<5>
J 0
(-5640 5435);
DISPLAY 0.659574 (-5640 5435);
PAINT MONO (-5640 5435);
DISPLAY INVISIBLE (-5640 5435);
FORCEPROP 1 LASTPIN (-5650 5425) BN 5
J 2
(-5638 5433);
DISPLAY 0.489362 (-5638 5433);
PAINT GREEN (-5638 5433);
FORCEPROP 2 LAST CDS_LIB mstr_standard
J 2
(-5700 5425);
DISPLAY 0.723404 (-5700 5425);
PAINT MONO (-5700 5425);
DISPLAY INVISIBLE (-5700 5425);
FORCEPROP 1 LAST BODY_TYPE PLUMBING
J 2
(-5700 5475);
DISPLAY 0.872340 (-5700 5475);
PAINT GREEN (-5700 5475);
DISPLAY INVISIBLE (-5700 5475);
FORCEPROP 1 LAST HDL_TAP TRUE
J 2
(-6025 5300);
DISPLAY 0.872340 (-6025 5300);
DISPLAY INVISIBLE (-6025 5300);
FORCEPROP 1 LAST PATH I252
J 2
(-5698 5425);
DISPLAY 0.872340 (-5698 5425);
PAINT GREEN (-5698 5425);
DISPLAY INVISIBLE (-5698 5425);
FORCEADD TAP..1
R 2
(-5900 5575);
FORCEPROP 3 LASTPIN (-5850 5575) SIG_NAME M_L_CPU1_SA_DQS_DN<3>
J 0
(-5840 5585);
DISPLAY 0.659574 (-5840 5585);
PAINT MONO (-5840 5585);
DISPLAY INVISIBLE (-5840 5585);
FORCEPROP 1 LASTPIN (-5850 5575) BN 3
J 2
(-5838 5583);
DISPLAY 0.489362 (-5838 5583);
PAINT GREEN (-5838 5583);
FORCEPROP 2 LAST CDS_LIB mstr_standard
J 2
(-5900 5575);
DISPLAY 0.723404 (-5900 5575);
PAINT MONO (-5900 5575);
DISPLAY INVISIBLE (-5900 5575);
FORCEPROP 1 LAST BODY_TYPE PLUMBING
J 2
(-5900 5625);
DISPLAY 0.872340 (-5900 5625);
PAINT GREEN (-5900 5625);
DISPLAY INVISIBLE (-5900 5625);
FORCEPROP 1 LAST HDL_TAP TRUE
J 2
(-6225 5450);
DISPLAY 0.872340 (-6225 5450);
DISPLAY INVISIBLE (-6225 5450);
FORCEPROP 1 LAST PATH I253
J 2
(-5898 5575);
DISPLAY 0.872340 (-5898 5575);
PAINT GREEN (-5898 5575);
DISPLAY INVISIBLE (-5898 5575);
FORCEADD TAP..1
R 2
(-5900 5475);
FORCEPROP 3 LASTPIN (-5850 5475) SIG_NAME M_L_CPU1_SA_DQS_DN<4>
J 0
(-5840 5485);
DISPLAY 0.659574 (-5840 5485);
PAINT MONO (-5840 5485);
DISPLAY INVISIBLE (-5840 5485);
FORCEPROP 1 LASTPIN (-5850 5475) BN 4
J 2
(-5838 5483);
DISPLAY 0.489362 (-5838 5483);
PAINT GREEN (-5838 5483);
FORCEPROP 2 LAST CDS_LIB mstr_standard
J 2
(-5900 5475);
DISPLAY 0.723404 (-5900 5475);
PAINT MONO (-5900 5475);
DISPLAY INVISIBLE (-5900 5475);
FORCEPROP 1 LAST BODY_TYPE PLUMBING
J 2
(-5900 5525);
DISPLAY 0.872340 (-5900 5525);
PAINT GREEN (-5900 5525);
DISPLAY INVISIBLE (-5900 5525);
FORCEPROP 1 LAST HDL_TAP TRUE
J 2
(-6225 5350);
DISPLAY 0.872340 (-6225 5350);
DISPLAY INVISIBLE (-6225 5350);
FORCEPROP 1 LAST PATH I254
J 2
(-5898 5475);
DISPLAY 0.872340 (-5898 5475);
PAINT GREEN (-5898 5475);
DISPLAY INVISIBLE (-5898 5475);
FORCEADD TAP..1
R 2
(-5700 5225);
FORCEPROP 3 LASTPIN (-5650 5225) SIG_NAME M_L_CPU1_SA_DQS_DP<7>
J 0
(-5640 5235);
DISPLAY 0.659574 (-5640 5235);
PAINT MONO (-5640 5235);
DISPLAY INVISIBLE (-5640 5235);
FORCEPROP 1 LASTPIN (-5650 5225) BN 7
J 2
(-5638 5233);
DISPLAY 0.489362 (-5638 5233);
PAINT GREEN (-5638 5233);
FORCEPROP 2 LAST CDS_LIB mstr_standard
J 2
(-5700 5225);
DISPLAY 0.723404 (-5700 5225);
PAINT MONO (-5700 5225);
DISPLAY INVISIBLE (-5700 5225);
FORCEPROP 1 LAST BODY_TYPE PLUMBING
J 2
(-5700 5275);
DISPLAY 0.872340 (-5700 5275);
PAINT GREEN (-5700 5275);
DISPLAY INVISIBLE (-5700 5275);
FORCEPROP 1 LAST HDL_TAP TRUE
J 2
(-6025 5100);
DISPLAY 0.872340 (-6025 5100);
DISPLAY INVISIBLE (-6025 5100);
FORCEPROP 1 LAST PATH I255
J 2
(-5698 5225);
DISPLAY 0.872340 (-5698 5225);
PAINT GREEN (-5698 5225);
DISPLAY INVISIBLE (-5698 5225);
FORCEADD TAP..1
R 2
(-5700 5325);
FORCEPROP 3 LASTPIN (-5650 5325) SIG_NAME M_L_CPU1_SA_DQS_DP<6>
J 0
(-5640 5335);
DISPLAY 0.659574 (-5640 5335);
PAINT MONO (-5640 5335);
DISPLAY INVISIBLE (-5640 5335);
FORCEPROP 1 LASTPIN (-5650 5325) BN 6
J 2
(-5638 5333);
DISPLAY 0.489362 (-5638 5333);
PAINT GREEN (-5638 5333);
FORCEPROP 2 LAST CDS_LIB mstr_standard
J 2
(-5700 5325);
DISPLAY 0.723404 (-5700 5325);
PAINT MONO (-5700 5325);
DISPLAY INVISIBLE (-5700 5325);
FORCEPROP 1 LAST BODY_TYPE PLUMBING
J 2
(-5700 5375);
DISPLAY 0.872340 (-5700 5375);
PAINT GREEN (-5700 5375);
DISPLAY INVISIBLE (-5700 5375);
FORCEPROP 1 LAST HDL_TAP TRUE
J 2
(-6025 5200);
DISPLAY 0.872340 (-6025 5200);
DISPLAY INVISIBLE (-6025 5200);
FORCEPROP 1 LAST PATH I256
J 2
(-5698 5325);
DISPLAY 0.872340 (-5698 5325);
PAINT GREEN (-5698 5325);
DISPLAY INVISIBLE (-5698 5325);
FORCEADD TAP..1
R 2
(-5700 5125);
FORCEPROP 3 LASTPIN (-5650 5125) SIG_NAME M_L_CPU1_SA_DQS_DP<8>
J 0
(-5640 5135);
DISPLAY 0.659574 (-5640 5135);
PAINT MONO (-5640 5135);
DISPLAY INVISIBLE (-5640 5135);
FORCEPROP 1 LASTPIN (-5650 5125) BN 8
J 2
(-5638 5133);
DISPLAY 0.489362 (-5638 5133);
PAINT GREEN (-5638 5133);
FORCEPROP 2 LAST CDS_LIB mstr_standard
J 2
(-5700 5125);
DISPLAY 0.723404 (-5700 5125);
PAINT MONO (-5700 5125);
DISPLAY INVISIBLE (-5700 5125);
FORCEPROP 1 LAST BODY_TYPE PLUMBING
J 2
(-5700 5175);
DISPLAY 0.872340 (-5700 5175);
PAINT GREEN (-5700 5175);
DISPLAY INVISIBLE (-5700 5175);
FORCEPROP 1 LAST HDL_TAP TRUE
J 2
(-6025 5000);
DISPLAY 0.872340 (-6025 5000);
DISPLAY INVISIBLE (-6025 5000);
FORCEPROP 1 LAST PATH I257
J 2
(-5698 5125);
DISPLAY 0.872340 (-5698 5125);
PAINT GREEN (-5698 5125);
DISPLAY INVISIBLE (-5698 5125);
FORCEADD TAP..1
R 2
(-5900 5275);
FORCEPROP 3 LASTPIN (-5850 5275) SIG_NAME M_L_CPU1_SA_DQS_DN<6>
J 0
(-5840 5285);
DISPLAY 0.659574 (-5840 5285);
PAINT MONO (-5840 5285);
DISPLAY INVISIBLE (-5840 5285);
FORCEPROP 1 LASTPIN (-5850 5275) BN 6
J 2
(-5838 5283);
DISPLAY 0.489362 (-5838 5283);
PAINT GREEN (-5838 5283);
FORCEPROP 2 LAST CDS_LIB mstr_standard
J 2
(-5900 5275);
DISPLAY 0.723404 (-5900 5275);
PAINT MONO (-5900 5275);
DISPLAY INVISIBLE (-5900 5275);
FORCEPROP 1 LAST BODY_TYPE PLUMBING
J 2
(-5900 5325);
DISPLAY 0.872340 (-5900 5325);
PAINT GREEN (-5900 5325);
DISPLAY INVISIBLE (-5900 5325);
FORCEPROP 1 LAST HDL_TAP TRUE
J 2
(-6225 5150);
DISPLAY 0.872340 (-6225 5150);
DISPLAY INVISIBLE (-6225 5150);
FORCEPROP 1 LAST PATH I258
J 2
(-5898 5275);
DISPLAY 0.872340 (-5898 5275);
PAINT GREEN (-5898 5275);
DISPLAY INVISIBLE (-5898 5275);
FORCEADD TAP..1
R 2
(-5900 5375);
FORCEPROP 3 LASTPIN (-5850 5375) SIG_NAME M_L_CPU1_SA_DQS_DN<5>
J 0
(-5840 5385);
DISPLAY 0.659574 (-5840 5385);
PAINT MONO (-5840 5385);
DISPLAY INVISIBLE (-5840 5385);
FORCEPROP 1 LASTPIN (-5850 5375) BN 5
J 2
(-5838 5383);
DISPLAY 0.489362 (-5838 5383);
PAINT GREEN (-5838 5383);
FORCEPROP 2 LAST CDS_LIB mstr_standard
J 2
(-5900 5375);
DISPLAY 0.723404 (-5900 5375);
PAINT MONO (-5900 5375);
DISPLAY INVISIBLE (-5900 5375);
FORCEPROP 1 LAST BODY_TYPE PLUMBING
J 2
(-5900 5425);
DISPLAY 0.872340 (-5900 5425);
PAINT GREEN (-5900 5425);
DISPLAY INVISIBLE (-5900 5425);
FORCEPROP 1 LAST HDL_TAP TRUE
J 2
(-6225 5250);
DISPLAY 0.872340 (-6225 5250);
DISPLAY INVISIBLE (-6225 5250);
FORCEPROP 1 LAST PATH I259
J 2
(-5898 5375);
DISPLAY 0.872340 (-5898 5375);
PAINT GREEN (-5898 5375);
DISPLAY INVISIBLE (-5898 5375);
FORCEADD TAP..1
R 2
(-5900 5175);
FORCEPROP 3 LASTPIN (-5850 5175) SIG_NAME M_L_CPU1_SA_DQS_DN<7>
J 0
(-5840 5185);
DISPLAY 0.659574 (-5840 5185);
PAINT MONO (-5840 5185);
DISPLAY INVISIBLE (-5840 5185);
FORCEPROP 1 LASTPIN (-5850 5175) BN 7
J 2
(-5838 5183);
DISPLAY 0.489362 (-5838 5183);
PAINT GREEN (-5838 5183);
FORCEPROP 2 LAST CDS_LIB mstr_standard
J 2
(-5900 5175);
DISPLAY 0.723404 (-5900 5175);
PAINT MONO (-5900 5175);
DISPLAY INVISIBLE (-5900 5175);
FORCEPROP 1 LAST BODY_TYPE PLUMBING
J 2
(-5900 5225);
DISPLAY 0.872340 (-5900 5225);
PAINT GREEN (-5900 5225);
DISPLAY INVISIBLE (-5900 5225);
FORCEPROP 1 LAST HDL_TAP TRUE
J 2
(-6225 5050);
DISPLAY 0.872340 (-6225 5050);
DISPLAY INVISIBLE (-6225 5050);
FORCEPROP 1 LAST PATH I260
J 2
(-5898 5175);
DISPLAY 0.872340 (-5898 5175);
PAINT GREEN (-5898 5175);
DISPLAY INVISIBLE (-5898 5175);
FORCEADD TAP..1
R 2
(-5700 4875);
FORCEPROP 3 LASTPIN (-5650 4875) SIG_NAME M_L_CPU1_SB_DQS_DP<0>
J 0
(-5640 4885);
DISPLAY 0.659574 (-5640 4885);
PAINT MONO (-5640 4885);
DISPLAY INVISIBLE (-5640 4885);
FORCEPROP 1 LASTPIN (-5650 4875) BN 0
J 2
(-5638 4883);
DISPLAY 0.489362 (-5638 4883);
PAINT GREEN (-5638 4883);
FORCEPROP 2 LAST CDS_LIB mstr_standard
J 2
(-5700 4875);
DISPLAY 0.723404 (-5700 4875);
PAINT MONO (-5700 4875);
DISPLAY INVISIBLE (-5700 4875);
FORCEPROP 1 LAST BODY_TYPE PLUMBING
J 2
(-5700 4925);
DISPLAY 0.872340 (-5700 4925);
PAINT GREEN (-5700 4925);
DISPLAY INVISIBLE (-5700 4925);
FORCEPROP 1 LAST HDL_TAP TRUE
J 2
(-6025 4750);
DISPLAY 0.872340 (-6025 4750);
DISPLAY INVISIBLE (-6025 4750);
FORCEPROP 1 LAST PATH I261
J 2
(-5698 4875);
DISPLAY 0.872340 (-5698 4875);
PAINT GREEN (-5698 4875);
DISPLAY INVISIBLE (-5698 4875);
FORCEADD TAP..1
R 2
(-5700 5025);
FORCEPROP 3 LASTPIN (-5650 5025) SIG_NAME M_L_CPU1_SA_DQS_DP<9>
J 0
(-5640 5035);
DISPLAY 0.659574 (-5640 5035);
PAINT MONO (-5640 5035);
DISPLAY INVISIBLE (-5640 5035);
FORCEPROP 1 LASTPIN (-5650 5025) BN 9
J 2
(-5638 5033);
DISPLAY 0.489362 (-5638 5033);
PAINT GREEN (-5638 5033);
FORCEPROP 2 LAST CDS_LIB mstr_standard
J 2
(-5700 5025);
DISPLAY 0.723404 (-5700 5025);
PAINT MONO (-5700 5025);
DISPLAY INVISIBLE (-5700 5025);
FORCEPROP 1 LAST BODY_TYPE PLUMBING
J 2
(-5700 5075);
DISPLAY 0.872340 (-5700 5075);
PAINT GREEN (-5700 5075);
DISPLAY INVISIBLE (-5700 5075);
FORCEPROP 1 LAST HDL_TAP TRUE
J 2
(-6025 4900);
DISPLAY 0.872340 (-6025 4900);
DISPLAY INVISIBLE (-6025 4900);
FORCEPROP 1 LAST PATH I262
J 2
(-5698 5025);
DISPLAY 0.872340 (-5698 5025);
PAINT GREEN (-5698 5025);
DISPLAY INVISIBLE (-5698 5025);
FORCEADD TAP..1
R 2
(-5900 5075);
FORCEPROP 3 LASTPIN (-5850 5075) SIG_NAME M_L_CPU1_SA_DQS_DN<8>
J 0
(-5840 5085);
DISPLAY 0.659574 (-5840 5085);
PAINT MONO (-5840 5085);
DISPLAY INVISIBLE (-5840 5085);
FORCEPROP 1 LASTPIN (-5850 5075) BN 8
J 2
(-5838 5083);
DISPLAY 0.489362 (-5838 5083);
PAINT GREEN (-5838 5083);
FORCEPROP 2 LAST CDS_LIB mstr_standard
J 2
(-5900 5075);
DISPLAY 0.723404 (-5900 5075);
PAINT MONO (-5900 5075);
DISPLAY INVISIBLE (-5900 5075);
FORCEPROP 1 LAST BODY_TYPE PLUMBING
J 2
(-5900 5125);
DISPLAY 0.872340 (-5900 5125);
PAINT GREEN (-5900 5125);
DISPLAY INVISIBLE (-5900 5125);
FORCEPROP 1 LAST HDL_TAP TRUE
J 2
(-6225 4950);
DISPLAY 0.872340 (-6225 4950);
DISPLAY INVISIBLE (-6225 4950);
FORCEPROP 1 LAST PATH I263
J 2
(-5898 5075);
DISPLAY 0.872340 (-5898 5075);
PAINT GREEN (-5898 5075);
DISPLAY INVISIBLE (-5898 5075);
FORCEADD TAP..1
R 2
(-5900 4975);
FORCEPROP 3 LASTPIN (-5850 4975) SIG_NAME M_L_CPU1_SA_DQS_DN<9>
J 0
(-5840 4985);
DISPLAY 0.659574 (-5840 4985);
PAINT MONO (-5840 4985);
DISPLAY INVISIBLE (-5840 4985);
FORCEPROP 1 LASTPIN (-5850 4975) BN 9
J 2
(-5838 4983);
DISPLAY 0.489362 (-5838 4983);
PAINT GREEN (-5838 4983);
FORCEPROP 2 LAST CDS_LIB mstr_standard
J 2
(-5900 4975);
DISPLAY 0.723404 (-5900 4975);
PAINT MONO (-5900 4975);
DISPLAY INVISIBLE (-5900 4975);
FORCEPROP 1 LAST BODY_TYPE PLUMBING
J 2
(-5900 5025);
DISPLAY 0.872340 (-5900 5025);
PAINT GREEN (-5900 5025);
DISPLAY INVISIBLE (-5900 5025);
FORCEPROP 1 LAST HDL_TAP TRUE
J 2
(-6225 4850);
DISPLAY 0.872340 (-6225 4850);
DISPLAY INVISIBLE (-6225 4850);
FORCEPROP 1 LAST PATH I264
J 2
(-5898 4975);
DISPLAY 0.872340 (-5898 4975);
PAINT GREEN (-5898 4975);
DISPLAY INVISIBLE (-5898 4975);
FORCEADD TAP..1
R 2
(-5700 4775);
FORCEPROP 3 LASTPIN (-5650 4775) SIG_NAME M_L_CPU1_SB_DQS_DP<1>
J 0
(-5640 4785);
DISPLAY 0.659574 (-5640 4785);
PAINT MONO (-5640 4785);
DISPLAY INVISIBLE (-5640 4785);
FORCEPROP 1 LASTPIN (-5650 4775) BN 1
J 2
(-5638 4783);
DISPLAY 0.489362 (-5638 4783);
PAINT GREEN (-5638 4783);
FORCEPROP 2 LAST CDS_LIB mstr_standard
J 2
(-5700 4775);
DISPLAY 0.723404 (-5700 4775);
PAINT MONO (-5700 4775);
DISPLAY INVISIBLE (-5700 4775);
FORCEPROP 1 LAST BODY_TYPE PLUMBING
J 2
(-5700 4825);
DISPLAY 0.872340 (-5700 4825);
PAINT GREEN (-5700 4825);
DISPLAY INVISIBLE (-5700 4825);
FORCEPROP 1 LAST HDL_TAP TRUE
J 2
(-6025 4650);
DISPLAY 0.872340 (-6025 4650);
DISPLAY INVISIBLE (-6025 4650);
FORCEPROP 1 LAST PATH I265
J 2
(-5698 4775);
DISPLAY 0.872340 (-5698 4775);
PAINT GREEN (-5698 4775);
DISPLAY INVISIBLE (-5698 4775);
FORCEADD TAP..1
R 2
(-5700 4675);
FORCEPROP 3 LASTPIN (-5650 4675) SIG_NAME M_L_CPU1_SB_DQS_DP<2>
J 0
(-5640 4685);
DISPLAY 0.659574 (-5640 4685);
PAINT MONO (-5640 4685);
DISPLAY INVISIBLE (-5640 4685);
FORCEPROP 1 LASTPIN (-5650 4675) BN 2
J 2
(-5638 4683);
DISPLAY 0.489362 (-5638 4683);
PAINT GREEN (-5638 4683);
FORCEPROP 2 LAST CDS_LIB mstr_standard
J 2
(-5700 4675);
DISPLAY 0.723404 (-5700 4675);
PAINT MONO (-5700 4675);
DISPLAY INVISIBLE (-5700 4675);
FORCEPROP 1 LAST BODY_TYPE PLUMBING
J 2
(-5700 4725);
DISPLAY 0.872340 (-5700 4725);
PAINT GREEN (-5700 4725);
DISPLAY INVISIBLE (-5700 4725);
FORCEPROP 1 LAST HDL_TAP TRUE
J 2
(-6025 4550);
DISPLAY 0.872340 (-6025 4550);
DISPLAY INVISIBLE (-6025 4550);
FORCEPROP 1 LAST PATH I266
J 2
(-5698 4675);
DISPLAY 0.872340 (-5698 4675);
PAINT GREEN (-5698 4675);
DISPLAY INVISIBLE (-5698 4675);
FORCEADD TAP..1
R 2
(-5900 4825);
FORCEPROP 3 LASTPIN (-5850 4825) SIG_NAME M_L_CPU1_SB_DQS_DN<0>
J 0
(-5840 4835);
DISPLAY 0.659574 (-5840 4835);
PAINT MONO (-5840 4835);
DISPLAY INVISIBLE (-5840 4835);
FORCEPROP 1 LASTPIN (-5850 4825) BN 0
J 2
(-5838 4833);
DISPLAY 0.489362 (-5838 4833);
PAINT GREEN (-5838 4833);
FORCEPROP 2 LAST CDS_LIB mstr_standard
J 2
(-5900 4825);
DISPLAY 0.723404 (-5900 4825);
PAINT MONO (-5900 4825);
DISPLAY INVISIBLE (-5900 4825);
FORCEPROP 1 LAST BODY_TYPE PLUMBING
J 2
(-5900 4875);
DISPLAY 0.872340 (-5900 4875);
PAINT GREEN (-5900 4875);
DISPLAY INVISIBLE (-5900 4875);
FORCEPROP 1 LAST HDL_TAP TRUE
J 2
(-6225 4700);
DISPLAY 0.872340 (-6225 4700);
DISPLAY INVISIBLE (-6225 4700);
FORCEPROP 1 LAST PATH I267
J 2
(-5898 4825);
DISPLAY 0.872340 (-5898 4825);
PAINT GREEN (-5898 4825);
DISPLAY INVISIBLE (-5898 4825);
FORCEADD TAP..1
R 2
(-5900 4725);
FORCEPROP 3 LASTPIN (-5850 4725) SIG_NAME M_L_CPU1_SB_DQS_DN<1>
J 0
(-5840 4735);
DISPLAY 0.659574 (-5840 4735);
PAINT MONO (-5840 4735);
DISPLAY INVISIBLE (-5840 4735);
FORCEPROP 1 LASTPIN (-5850 4725) BN 1
J 2
(-5838 4733);
DISPLAY 0.489362 (-5838 4733);
PAINT GREEN (-5838 4733);
FORCEPROP 2 LAST CDS_LIB mstr_standard
J 2
(-5900 4725);
DISPLAY 0.723404 (-5900 4725);
PAINT MONO (-5900 4725);
DISPLAY INVISIBLE (-5900 4725);
FORCEPROP 1 LAST BODY_TYPE PLUMBING
J 2
(-5900 4775);
DISPLAY 0.872340 (-5900 4775);
PAINT GREEN (-5900 4775);
DISPLAY INVISIBLE (-5900 4775);
FORCEPROP 1 LAST HDL_TAP TRUE
J 2
(-6225 4600);
DISPLAY 0.872340 (-6225 4600);
DISPLAY INVISIBLE (-6225 4600);
FORCEPROP 1 LAST PATH I268
J 2
(-5898 4725);
DISPLAY 0.872340 (-5898 4725);
PAINT GREEN (-5898 4725);
DISPLAY INVISIBLE (-5898 4725);
FORCEADD TAP..1
R 2
(-5900 4625);
FORCEPROP 3 LASTPIN (-5850 4625) SIG_NAME M_L_CPU1_SB_DQS_DN<2>
J 0
(-5840 4635);
DISPLAY 0.659574 (-5840 4635);
PAINT MONO (-5840 4635);
DISPLAY INVISIBLE (-5840 4635);
FORCEPROP 1 LASTPIN (-5850 4625) BN 2
J 2
(-5838 4633);
DISPLAY 0.489362 (-5838 4633);
PAINT GREEN (-5838 4633);
FORCEPROP 2 LAST CDS_LIB mstr_standard
J 2
(-5900 4625);
DISPLAY 0.723404 (-5900 4625);
PAINT MONO (-5900 4625);
DISPLAY INVISIBLE (-5900 4625);
FORCEPROP 1 LAST BODY_TYPE PLUMBING
J 2
(-5900 4675);
DISPLAY 0.872340 (-5900 4675);
PAINT GREEN (-5900 4675);
DISPLAY INVISIBLE (-5900 4675);
FORCEPROP 1 LAST HDL_TAP TRUE
J 2
(-6225 4500);
DISPLAY 0.872340 (-6225 4500);
DISPLAY INVISIBLE (-6225 4500);
FORCEPROP 1 LAST PATH I269
J 2
(-5898 4625);
DISPLAY 0.872340 (-5898 4625);
PAINT GREEN (-5898 4625);
DISPLAY INVISIBLE (-5898 4625);
FORCEADD TAP..1
R 2
(-5700 4475);
FORCEPROP 3 LASTPIN (-5650 4475) SIG_NAME M_L_CPU1_SB_DQS_DP<4>
J 0
(-5640 4485);
DISPLAY 0.659574 (-5640 4485);
PAINT MONO (-5640 4485);
DISPLAY INVISIBLE (-5640 4485);
FORCEPROP 1 LASTPIN (-5650 4475) BN 4
J 2
(-5638 4483);
DISPLAY 0.489362 (-5638 4483);
PAINT GREEN (-5638 4483);
FORCEPROP 2 LAST CDS_LIB mstr_standard
J 2
(-5700 4475);
DISPLAY 0.723404 (-5700 4475);
PAINT MONO (-5700 4475);
DISPLAY INVISIBLE (-5700 4475);
FORCEPROP 1 LAST BODY_TYPE PLUMBING
J 2
(-5700 4525);
DISPLAY 0.872340 (-5700 4525);
PAINT GREEN (-5700 4525);
DISPLAY INVISIBLE (-5700 4525);
FORCEPROP 1 LAST HDL_TAP TRUE
J 2
(-6025 4350);
DISPLAY 0.872340 (-6025 4350);
DISPLAY INVISIBLE (-6025 4350);
FORCEPROP 1 LAST PATH I270
J 2
(-5698 4475);
DISPLAY 0.872340 (-5698 4475);
PAINT GREEN (-5698 4475);
DISPLAY INVISIBLE (-5698 4475);
FORCEADD TAP..1
R 2
(-5700 4575);
FORCEPROP 3 LASTPIN (-5650 4575) SIG_NAME M_L_CPU1_SB_DQS_DP<3>
J 0
(-5640 4585);
DISPLAY 0.659574 (-5640 4585);
PAINT MONO (-5640 4585);
DISPLAY INVISIBLE (-5640 4585);
FORCEPROP 1 LASTPIN (-5650 4575) BN 3
J 2
(-5638 4583);
DISPLAY 0.489362 (-5638 4583);
PAINT GREEN (-5638 4583);
FORCEPROP 2 LAST CDS_LIB mstr_standard
J 2
(-5700 4575);
DISPLAY 0.723404 (-5700 4575);
PAINT MONO (-5700 4575);
DISPLAY INVISIBLE (-5700 4575);
FORCEPROP 1 LAST BODY_TYPE PLUMBING
J 2
(-5700 4625);
DISPLAY 0.872340 (-5700 4625);
PAINT GREEN (-5700 4625);
DISPLAY INVISIBLE (-5700 4625);
FORCEPROP 1 LAST HDL_TAP TRUE
J 2
(-6025 4450);
DISPLAY 0.872340 (-6025 4450);
DISPLAY INVISIBLE (-6025 4450);
FORCEPROP 1 LAST PATH I271
J 2
(-5698 4575);
DISPLAY 0.872340 (-5698 4575);
PAINT GREEN (-5698 4575);
DISPLAY INVISIBLE (-5698 4575);
FORCEADD TAP..1
R 2
(-5700 4375);
FORCEPROP 3 LASTPIN (-5650 4375) SIG_NAME M_L_CPU1_SB_DQS_DP<5>
J 0
(-5640 4385);
DISPLAY 0.659574 (-5640 4385);
PAINT MONO (-5640 4385);
DISPLAY INVISIBLE (-5640 4385);
FORCEPROP 1 LASTPIN (-5650 4375) BN 5
J 2
(-5638 4383);
DISPLAY 0.489362 (-5638 4383);
PAINT GREEN (-5638 4383);
FORCEPROP 2 LAST CDS_LIB mstr_standard
J 2
(-5700 4375);
DISPLAY 0.723404 (-5700 4375);
PAINT MONO (-5700 4375);
DISPLAY INVISIBLE (-5700 4375);
FORCEPROP 1 LAST BODY_TYPE PLUMBING
J 2
(-5700 4425);
DISPLAY 0.872340 (-5700 4425);
PAINT GREEN (-5700 4425);
DISPLAY INVISIBLE (-5700 4425);
FORCEPROP 1 LAST HDL_TAP TRUE
J 2
(-6025 4250);
DISPLAY 0.872340 (-6025 4250);
DISPLAY INVISIBLE (-6025 4250);
FORCEPROP 1 LAST PATH I272
J 2
(-5698 4375);
DISPLAY 0.872340 (-5698 4375);
PAINT GREEN (-5698 4375);
DISPLAY INVISIBLE (-5698 4375);
FORCEADD TAP..1
R 2
(-5900 4525);
FORCEPROP 3 LASTPIN (-5850 4525) SIG_NAME M_L_CPU1_SB_DQS_DN<3>
J 0
(-5840 4535);
DISPLAY 0.659574 (-5840 4535);
PAINT MONO (-5840 4535);
DISPLAY INVISIBLE (-5840 4535);
FORCEPROP 1 LASTPIN (-5850 4525) BN 3
J 2
(-5838 4533);
DISPLAY 0.489362 (-5838 4533);
PAINT GREEN (-5838 4533);
FORCEPROP 2 LAST CDS_LIB mstr_standard
J 2
(-5900 4525);
DISPLAY 0.723404 (-5900 4525);
PAINT MONO (-5900 4525);
DISPLAY INVISIBLE (-5900 4525);
FORCEPROP 1 LAST BODY_TYPE PLUMBING
J 2
(-5900 4575);
DISPLAY 0.872340 (-5900 4575);
PAINT GREEN (-5900 4575);
DISPLAY INVISIBLE (-5900 4575);
FORCEPROP 1 LAST HDL_TAP TRUE
J 2
(-6225 4400);
DISPLAY 0.872340 (-6225 4400);
DISPLAY INVISIBLE (-6225 4400);
FORCEPROP 1 LAST PATH I273
J 2
(-5898 4525);
DISPLAY 0.872340 (-5898 4525);
PAINT GREEN (-5898 4525);
DISPLAY INVISIBLE (-5898 4525);
FORCEADD TAP..1
R 2
(-5900 4425);
FORCEPROP 3 LASTPIN (-5850 4425) SIG_NAME M_L_CPU1_SB_DQS_DN<4>
J 0
(-5840 4435);
DISPLAY 0.659574 (-5840 4435);
PAINT MONO (-5840 4435);
DISPLAY INVISIBLE (-5840 4435);
FORCEPROP 1 LASTPIN (-5850 4425) BN 4
J 2
(-5838 4433);
DISPLAY 0.489362 (-5838 4433);
PAINT GREEN (-5838 4433);
FORCEPROP 2 LAST CDS_LIB mstr_standard
J 2
(-5900 4425);
DISPLAY 0.723404 (-5900 4425);
PAINT MONO (-5900 4425);
DISPLAY INVISIBLE (-5900 4425);
FORCEPROP 1 LAST BODY_TYPE PLUMBING
J 2
(-5900 4475);
DISPLAY 0.872340 (-5900 4475);
PAINT GREEN (-5900 4475);
DISPLAY INVISIBLE (-5900 4475);
FORCEPROP 1 LAST HDL_TAP TRUE
J 2
(-6225 4300);
DISPLAY 0.872340 (-6225 4300);
DISPLAY INVISIBLE (-6225 4300);
FORCEPROP 1 LAST PATH I274
J 2
(-5898 4425);
DISPLAY 0.872340 (-5898 4425);
PAINT GREEN (-5898 4425);
DISPLAY INVISIBLE (-5898 4425);
FORCEADD TAP..1
R 2
(-5700 4275);
FORCEPROP 3 LASTPIN (-5650 4275) SIG_NAME M_L_CPU1_SB_DQS_DP<6>
J 0
(-5640 4285);
DISPLAY 0.659574 (-5640 4285);
PAINT MONO (-5640 4285);
DISPLAY INVISIBLE (-5640 4285);
FORCEPROP 1 LASTPIN (-5650 4275) BN 6
J 2
(-5638 4283);
DISPLAY 0.489362 (-5638 4283);
PAINT GREEN (-5638 4283);
FORCEPROP 2 LAST CDS_LIB mstr_standard
J 2
(-5700 4275);
DISPLAY 0.723404 (-5700 4275);
PAINT MONO (-5700 4275);
DISPLAY INVISIBLE (-5700 4275);
FORCEPROP 1 LAST BODY_TYPE PLUMBING
J 2
(-5700 4325);
DISPLAY 0.872340 (-5700 4325);
PAINT GREEN (-5700 4325);
DISPLAY INVISIBLE (-5700 4325);
FORCEPROP 1 LAST HDL_TAP TRUE
J 2
(-6025 4150);
DISPLAY 0.872340 (-6025 4150);
DISPLAY INVISIBLE (-6025 4150);
FORCEPROP 1 LAST PATH I275
J 2
(-5698 4275);
DISPLAY 0.872340 (-5698 4275);
PAINT GREEN (-5698 4275);
DISPLAY INVISIBLE (-5698 4275);
FORCEADD TAP..1
R 2
(-5700 4175);
FORCEPROP 3 LASTPIN (-5650 4175) SIG_NAME M_L_CPU1_SB_DQS_DP<7>
J 0
(-5640 4185);
DISPLAY 0.659574 (-5640 4185);
PAINT MONO (-5640 4185);
DISPLAY INVISIBLE (-5640 4185);
FORCEPROP 1 LASTPIN (-5650 4175) BN 7
J 2
(-5638 4183);
DISPLAY 0.489362 (-5638 4183);
PAINT GREEN (-5638 4183);
FORCEPROP 2 LAST CDS_LIB mstr_standard
J 2
(-5700 4175);
DISPLAY 0.723404 (-5700 4175);
PAINT MONO (-5700 4175);
DISPLAY INVISIBLE (-5700 4175);
FORCEPROP 1 LAST BODY_TYPE PLUMBING
J 2
(-5700 4225);
DISPLAY 0.872340 (-5700 4225);
PAINT GREEN (-5700 4225);
DISPLAY INVISIBLE (-5700 4225);
FORCEPROP 1 LAST HDL_TAP TRUE
J 2
(-6025 4050);
DISPLAY 0.872340 (-6025 4050);
DISPLAY INVISIBLE (-6025 4050);
FORCEPROP 1 LAST PATH I276
J 2
(-5698 4175);
DISPLAY 0.872340 (-5698 4175);
PAINT GREEN (-5698 4175);
DISPLAY INVISIBLE (-5698 4175);
FORCEADD TAP..1
R 2
(-5900 4225);
FORCEPROP 3 LASTPIN (-5850 4225) SIG_NAME M_L_CPU1_SB_DQS_DN<6>
J 0
(-5840 4235);
DISPLAY 0.659574 (-5840 4235);
PAINT MONO (-5840 4235);
DISPLAY INVISIBLE (-5840 4235);
FORCEPROP 1 LASTPIN (-5850 4225) BN 6
J 2
(-5838 4233);
DISPLAY 0.489362 (-5838 4233);
PAINT GREEN (-5838 4233);
FORCEPROP 2 LAST CDS_LIB mstr_standard
J 2
(-5900 4225);
DISPLAY 0.723404 (-5900 4225);
PAINT MONO (-5900 4225);
DISPLAY INVISIBLE (-5900 4225);
FORCEPROP 1 LAST BODY_TYPE PLUMBING
J 2
(-5900 4275);
DISPLAY 0.872340 (-5900 4275);
PAINT GREEN (-5900 4275);
DISPLAY INVISIBLE (-5900 4275);
FORCEPROP 1 LAST HDL_TAP TRUE
J 2
(-6225 4100);
DISPLAY 0.872340 (-6225 4100);
DISPLAY INVISIBLE (-6225 4100);
FORCEPROP 1 LAST PATH I277
J 2
(-5898 4225);
DISPLAY 0.872340 (-5898 4225);
PAINT GREEN (-5898 4225);
DISPLAY INVISIBLE (-5898 4225);
FORCEADD TAP..1
R 2
(-5900 4325);
FORCEPROP 3 LASTPIN (-5850 4325) SIG_NAME M_L_CPU1_SB_DQS_DN<5>
J 0
(-5840 4335);
DISPLAY 0.659574 (-5840 4335);
PAINT MONO (-5840 4335);
DISPLAY INVISIBLE (-5840 4335);
FORCEPROP 1 LASTPIN (-5850 4325) BN 5
J 2
(-5838 4333);
DISPLAY 0.489362 (-5838 4333);
PAINT GREEN (-5838 4333);
FORCEPROP 2 LAST CDS_LIB mstr_standard
J 2
(-5900 4325);
DISPLAY 0.723404 (-5900 4325);
PAINT MONO (-5900 4325);
DISPLAY INVISIBLE (-5900 4325);
FORCEPROP 1 LAST BODY_TYPE PLUMBING
J 2
(-5900 4375);
DISPLAY 0.872340 (-5900 4375);
PAINT GREEN (-5900 4375);
DISPLAY INVISIBLE (-5900 4375);
FORCEPROP 1 LAST HDL_TAP TRUE
J 2
(-6225 4200);
DISPLAY 0.872340 (-6225 4200);
DISPLAY INVISIBLE (-6225 4200);
FORCEPROP 1 LAST PATH I278
J 2
(-5898 4325);
DISPLAY 0.872340 (-5898 4325);
PAINT GREEN (-5898 4325);
DISPLAY INVISIBLE (-5898 4325);
FORCEADD TAP..1
R 2
(-5900 4125);
FORCEPROP 3 LASTPIN (-5850 4125) SIG_NAME M_L_CPU1_SB_DQS_DN<7>
J 0
(-5840 4135);
DISPLAY 0.659574 (-5840 4135);
PAINT MONO (-5840 4135);
DISPLAY INVISIBLE (-5840 4135);
FORCEPROP 1 LASTPIN (-5850 4125) BN 7
J 2
(-5838 4133);
DISPLAY 0.489362 (-5838 4133);
PAINT GREEN (-5838 4133);
FORCEPROP 2 LAST CDS_LIB mstr_standard
J 2
(-5900 4125);
DISPLAY 0.723404 (-5900 4125);
PAINT MONO (-5900 4125);
DISPLAY INVISIBLE (-5900 4125);
FORCEPROP 1 LAST BODY_TYPE PLUMBING
J 2
(-5900 4175);
DISPLAY 0.872340 (-5900 4175);
PAINT GREEN (-5900 4175);
DISPLAY INVISIBLE (-5900 4175);
FORCEPROP 1 LAST HDL_TAP TRUE
J 2
(-6225 4000);
DISPLAY 0.872340 (-6225 4000);
DISPLAY INVISIBLE (-6225 4000);
FORCEPROP 1 LAST PATH I279
J 2
(-5898 4125);
DISPLAY 0.872340 (-5898 4125);
PAINT GREEN (-5898 4125);
DISPLAY INVISIBLE (-5898 4125);
FORCEADD OFFPAGE..3
R 2
(-6600 5900);
FORCEPROP 2 LAST $XR0 108 
J 0
(-6910 5900);
DISPLAY 0.638298 (-6910 5900);
PAINT MONO (-6910 5900);
FORCEPROP 2 LAST PATH I280
J 0
(-6875 5950);
DISPLAY 1.021277 (-6875 5950);
DISPLAY INVISIBLE (-6875 5950);
FORCEPROP 1 LAST COMMENT_BODY TRUE
J 2
(-6550 5800);
DISPLAY 0.872340 (-6550 5800);
PAINT GREEN (-6550 5800);
DISPLAY INVISIBLE (-6550 5800);
FORCEPROP 1 LAST OFFPAGE TRUE
J 2
(-6925 5775);
DISPLAY 0.872340 (-6925 5775);
PAINT GREEN (-6925 5775);
DISPLAY INVISIBLE (-6925 5775);
FORCEPROP 2 LAST CDS_LIB standard
J 0
(-6600 5900);
DISPLAY INVISIBLE (-6600 5900);
FORCEADD OFFPAGE..3
R 2
(-6600 5950);
FORCEPROP 2 LAST $XR0 108 
J 0
(-6910 5950);
DISPLAY 0.638298 (-6910 5950);
PAINT MONO (-6910 5950);
FORCEPROP 2 LAST PATH I281
J 0
(-6875 6000);
DISPLAY 1.021277 (-6875 6000);
DISPLAY INVISIBLE (-6875 6000);
FORCEPROP 1 LAST COMMENT_BODY TRUE
J 2
(-6550 5850);
DISPLAY 0.872340 (-6550 5850);
PAINT GREEN (-6550 5850);
DISPLAY INVISIBLE (-6550 5850);
FORCEPROP 1 LAST OFFPAGE TRUE
J 2
(-6925 5825);
DISPLAY 0.872340 (-6925 5825);
PAINT GREEN (-6925 5825);
DISPLAY INVISIBLE (-6925 5825);
FORCEPROP 2 LAST CDS_LIB standard
J 0
(-6600 5950);
DISPLAY INVISIBLE (-6600 5950);
FORCEADD OFFPAGE..3
R 2
(-6600 4900);
FORCEPROP 2 LAST $XR0 108 
J 0
(-6910 4900);
DISPLAY 0.638298 (-6910 4900);
PAINT MONO (-6910 4900);
FORCEPROP 2 LAST PATH I282
J 0
(-6875 4950);
DISPLAY 1.021277 (-6875 4950);
DISPLAY INVISIBLE (-6875 4950);
FORCEPROP 1 LAST COMMENT_BODY TRUE
J 2
(-6550 4800);
DISPLAY 0.872340 (-6550 4800);
PAINT GREEN (-6550 4800);
DISPLAY INVISIBLE (-6550 4800);
FORCEPROP 1 LAST OFFPAGE TRUE
J 2
(-6925 4775);
DISPLAY 0.872340 (-6925 4775);
PAINT GREEN (-6925 4775);
DISPLAY INVISIBLE (-6925 4775);
FORCEPROP 2 LAST CDS_LIB standard
J 0
(-6600 4900);
DISPLAY INVISIBLE (-6600 4900);
FORCEADD OFFPAGE..3
R 2
(-6600 4850);
FORCEPROP 2 LAST $XR0 108 
J 0
(-6910 4850);
DISPLAY 0.638298 (-6910 4850);
PAINT MONO (-6910 4850);
FORCEPROP 2 LAST PATH I283
J 0
(-6875 4900);
DISPLAY 1.021277 (-6875 4900);
DISPLAY INVISIBLE (-6875 4900);
FORCEPROP 1 LAST COMMENT_BODY TRUE
J 2
(-6550 4750);
DISPLAY 0.872340 (-6550 4750);
PAINT GREEN (-6550 4750);
DISPLAY INVISIBLE (-6550 4750);
FORCEPROP 1 LAST OFFPAGE TRUE
J 2
(-6925 4725);
DISPLAY 0.872340 (-6925 4725);
PAINT GREEN (-6925 4725);
DISPLAY INVISIBLE (-6925 4725);
FORCEPROP 2 LAST CDS_LIB standard
J 0
(-6600 4850);
DISPLAY INVISIBLE (-6600 4850);
FORCEADD TAP..1
R 2
(-5700 4075);
FORCEPROP 3 LASTPIN (-5650 4075) SIG_NAME M_L_CPU1_SB_DQS_DP<8>
J 0
(-5640 4085);
DISPLAY 0.659574 (-5640 4085);
PAINT MONO (-5640 4085);
DISPLAY INVISIBLE (-5640 4085);
FORCEPROP 1 LASTPIN (-5650 4075) BN 8
J 2
(-5638 4083);
DISPLAY 0.489362 (-5638 4083);
PAINT GREEN (-5638 4083);
FORCEPROP 2 LAST CDS_LIB mstr_standard
J 2
(-5700 4075);
DISPLAY 0.723404 (-5700 4075);
PAINT MONO (-5700 4075);
DISPLAY INVISIBLE (-5700 4075);
FORCEPROP 1 LAST BODY_TYPE PLUMBING
J 2
(-5700 4125);
DISPLAY 0.872340 (-5700 4125);
PAINT GREEN (-5700 4125);
DISPLAY INVISIBLE (-5700 4125);
FORCEPROP 1 LAST HDL_TAP TRUE
J 2
(-6025 3950);
DISPLAY 0.872340 (-6025 3950);
DISPLAY INVISIBLE (-6025 3950);
FORCEPROP 1 LAST PATH I284
J 2
(-5698 4075);
DISPLAY 0.872340 (-5698 4075);
PAINT GREEN (-5698 4075);
DISPLAY INVISIBLE (-5698 4075);
FORCEADD TAP..1
R 2
(-5700 3975);
FORCEPROP 3 LASTPIN (-5650 3975) SIG_NAME M_L_CPU1_SB_DQS_DP<9>
J 0
(-5640 3985);
DISPLAY 0.659574 (-5640 3985);
PAINT MONO (-5640 3985);
DISPLAY INVISIBLE (-5640 3985);
FORCEPROP 1 LASTPIN (-5650 3975) BN 9
J 2
(-5638 3983);
DISPLAY 0.489362 (-5638 3983);
PAINT GREEN (-5638 3983);
FORCEPROP 2 LAST CDS_LIB mstr_standard
J 2
(-5700 3975);
DISPLAY 0.723404 (-5700 3975);
PAINT MONO (-5700 3975);
DISPLAY INVISIBLE (-5700 3975);
FORCEPROP 1 LAST BODY_TYPE PLUMBING
J 2
(-5700 4025);
DISPLAY 0.872340 (-5700 4025);
PAINT GREEN (-5700 4025);
DISPLAY INVISIBLE (-5700 4025);
FORCEPROP 1 LAST HDL_TAP TRUE
J 2
(-6025 3850);
DISPLAY 0.872340 (-6025 3850);
DISPLAY INVISIBLE (-6025 3850);
FORCEPROP 1 LAST PATH I285
J 2
(-5698 3975);
DISPLAY 0.872340 (-5698 3975);
PAINT GREEN (-5698 3975);
DISPLAY INVISIBLE (-5698 3975);
FORCEADD TAP..1
R 2
(-5900 4025);
FORCEPROP 3 LASTPIN (-5850 4025) SIG_NAME M_L_CPU1_SB_DQS_DN<8>
J 0
(-5840 4035);
DISPLAY 0.659574 (-5840 4035);
PAINT MONO (-5840 4035);
DISPLAY INVISIBLE (-5840 4035);
FORCEPROP 1 LASTPIN (-5850 4025) BN 8
J 2
(-5838 4033);
DISPLAY 0.489362 (-5838 4033);
PAINT GREEN (-5838 4033);
FORCEPROP 2 LAST CDS_LIB mstr_standard
J 2
(-5900 4025);
DISPLAY 0.723404 (-5900 4025);
PAINT MONO (-5900 4025);
DISPLAY INVISIBLE (-5900 4025);
FORCEPROP 1 LAST BODY_TYPE PLUMBING
J 2
(-5900 4075);
DISPLAY 0.872340 (-5900 4075);
PAINT GREEN (-5900 4075);
DISPLAY INVISIBLE (-5900 4075);
FORCEPROP 1 LAST HDL_TAP TRUE
J 2
(-6225 3900);
DISPLAY 0.872340 (-6225 3900);
DISPLAY INVISIBLE (-6225 3900);
FORCEPROP 1 LAST PATH I286
J 2
(-5898 4025);
DISPLAY 0.872340 (-5898 4025);
PAINT GREEN (-5898 4025);
DISPLAY INVISIBLE (-5898 4025);
FORCEADD TAP..1
R 2
(-5900 3925);
FORCEPROP 3 LASTPIN (-5850 3925) SIG_NAME M_L_CPU1_SB_DQS_DN<9>
J 0
(-5840 3935);
DISPLAY 0.659574 (-5840 3935);
PAINT MONO (-5840 3935);
DISPLAY INVISIBLE (-5840 3935);
FORCEPROP 1 LASTPIN (-5850 3925) BN 9
J 2
(-5838 3933);
DISPLAY 0.489362 (-5838 3933);
PAINT GREEN (-5838 3933);
FORCEPROP 2 LAST CDS_LIB mstr_standard
J 2
(-5900 3925);
DISPLAY 0.723404 (-5900 3925);
PAINT MONO (-5900 3925);
DISPLAY INVISIBLE (-5900 3925);
FORCEPROP 1 LAST BODY_TYPE PLUMBING
J 2
(-5900 3975);
DISPLAY 0.872340 (-5900 3975);
PAINT GREEN (-5900 3975);
DISPLAY INVISIBLE (-5900 3975);
FORCEPROP 1 LAST HDL_TAP TRUE
J 2
(-6225 3800);
DISPLAY 0.872340 (-6225 3800);
DISPLAY INVISIBLE (-6225 3800);
FORCEPROP 1 LAST PATH I287
J 2
(-5898 3925);
DISPLAY 0.872340 (-5898 3925);
PAINT GREEN (-5898 3925);
DISPLAY INVISIBLE (-5898 3925);
FORCEADD TAP..1
R 2
(-5900 3725);
FORCEPROP 3 LASTPIN (-5850 3725) SIG_NAME M_L_CPU1_SA_CA<1>
J 0
(-5840 3735);
DISPLAY 0.659574 (-5840 3735);
PAINT MONO (-5840 3735);
DISPLAY INVISIBLE (-5840 3735);
FORCEPROP 1 LASTPIN (-5850 3725) BN 1
J 2
(-5838 3733);
DISPLAY 0.489362 (-5838 3733);
PAINT GREEN (-5838 3733);
FORCEPROP 2 LAST CDS_LIB mstr_standard
J 0
(-5900 3725);
DISPLAY 0.723404 (-5900 3725);
PAINT MONO (-5900 3725);
DISPLAY INVISIBLE (-5900 3725);
FORCEPROP 1 LAST BODY_TYPE PLUMBING
J 2
(-5900 3775);
DISPLAY 0.872340 (-5900 3775);
PAINT GREEN (-5900 3775);
DISPLAY INVISIBLE (-5900 3775);
FORCEPROP 1 LAST HDL_TAP TRUE
J 2
(-6225 3600);
DISPLAY 0.872340 (-6225 3600);
DISPLAY INVISIBLE (-6225 3600);
FORCEPROP 1 LAST PATH I288
J 2
(-5898 3725);
DISPLAY 0.872340 (-5898 3725);
PAINT GREEN (-5898 3725);
DISPLAY INVISIBLE (-5898 3725);
FORCEADD TAP..1
R 2
(-5900 3775);
FORCEPROP 3 LASTPIN (-5850 3775) SIG_NAME M_L_CPU1_SA_CA<0>
J 0
(-5840 3785);
DISPLAY 0.659574 (-5840 3785);
PAINT MONO (-5840 3785);
DISPLAY INVISIBLE (-5840 3785);
FORCEPROP 1 LASTPIN (-5850 3775) BN 0
J 2
(-5838 3783);
DISPLAY 0.489362 (-5838 3783);
PAINT GREEN (-5838 3783);
FORCEPROP 2 LAST CDS_LIB mstr_standard
J 0
(-5900 3775);
DISPLAY 0.723404 (-5900 3775);
PAINT MONO (-5900 3775);
DISPLAY INVISIBLE (-5900 3775);
FORCEPROP 1 LAST BODY_TYPE PLUMBING
J 2
(-5900 3825);
DISPLAY 0.872340 (-5900 3825);
PAINT GREEN (-5900 3825);
DISPLAY INVISIBLE (-5900 3825);
FORCEPROP 1 LAST HDL_TAP TRUE
J 2
(-6225 3650);
DISPLAY 0.872340 (-6225 3650);
DISPLAY INVISIBLE (-6225 3650);
FORCEPROP 1 LAST PATH I289
J 2
(-5898 3775);
DISPLAY 0.872340 (-5898 3775);
PAINT GREEN (-5898 3775);
DISPLAY INVISIBLE (-5898 3775);
FORCEADD TAP..1
R 2
(-5900 3625);
FORCEPROP 3 LASTPIN (-5850 3625) SIG_NAME M_L_CPU1_SA_CA<3>
J 0
(-5840 3635);
DISPLAY 0.659574 (-5840 3635);
PAINT MONO (-5840 3635);
DISPLAY INVISIBLE (-5840 3635);
FORCEPROP 1 LASTPIN (-5850 3625) BN 3
J 2
(-5838 3633);
DISPLAY 0.489362 (-5838 3633);
PAINT GREEN (-5838 3633);
FORCEPROP 2 LAST CDS_LIB mstr_standard
J 0
(-5900 3625);
DISPLAY 0.723404 (-5900 3625);
PAINT MONO (-5900 3625);
DISPLAY INVISIBLE (-5900 3625);
FORCEPROP 1 LAST BODY_TYPE PLUMBING
J 2
(-5900 3675);
DISPLAY 0.872340 (-5900 3675);
PAINT GREEN (-5900 3675);
DISPLAY INVISIBLE (-5900 3675);
FORCEPROP 1 LAST HDL_TAP TRUE
J 2
(-6225 3500);
DISPLAY 0.872340 (-6225 3500);
DISPLAY INVISIBLE (-6225 3500);
FORCEPROP 1 LAST PATH I290
J 2
(-5898 3625);
DISPLAY 0.872340 (-5898 3625);
PAINT GREEN (-5898 3625);
DISPLAY INVISIBLE (-5898 3625);
FORCEADD TAP..1
R 2
(-5900 3675);
FORCEPROP 3 LASTPIN (-5850 3675) SIG_NAME M_L_CPU1_SA_CA<2>
J 0
(-5840 3685);
DISPLAY 0.659574 (-5840 3685);
PAINT MONO (-5840 3685);
DISPLAY INVISIBLE (-5840 3685);
FORCEPROP 1 LASTPIN (-5850 3675) BN 2
J 2
(-5838 3683);
DISPLAY 0.489362 (-5838 3683);
PAINT GREEN (-5838 3683);
FORCEPROP 2 LAST CDS_LIB mstr_standard
J 0
(-5900 3675);
DISPLAY 0.723404 (-5900 3675);
PAINT MONO (-5900 3675);
DISPLAY INVISIBLE (-5900 3675);
FORCEPROP 1 LAST BODY_TYPE PLUMBING
J 2
(-5900 3725);
DISPLAY 0.872340 (-5900 3725);
PAINT GREEN (-5900 3725);
DISPLAY INVISIBLE (-5900 3725);
FORCEPROP 1 LAST HDL_TAP TRUE
J 2
(-6225 3550);
DISPLAY 0.872340 (-6225 3550);
DISPLAY INVISIBLE (-6225 3550);
FORCEPROP 1 LAST PATH I291
J 2
(-5898 3675);
DISPLAY 0.872340 (-5898 3675);
PAINT GREEN (-5898 3675);
DISPLAY INVISIBLE (-5898 3675);
FORCEADD TAP..1
R 2
(-5900 3475);
FORCEPROP 3 LASTPIN (-5850 3475) SIG_NAME M_L_CPU1_SA_CA<6>
J 0
(-5840 3485);
DISPLAY 0.659574 (-5840 3485);
PAINT MONO (-5840 3485);
DISPLAY INVISIBLE (-5840 3485);
FORCEPROP 1 LASTPIN (-5850 3475) BN 6
J 2
(-5838 3483);
DISPLAY 0.489362 (-5838 3483);
PAINT GREEN (-5838 3483);
FORCEPROP 2 LAST CDS_LIB mstr_standard
J 0
(-5900 3475);
DISPLAY 0.723404 (-5900 3475);
PAINT MONO (-5900 3475);
DISPLAY INVISIBLE (-5900 3475);
FORCEPROP 1 LAST BODY_TYPE PLUMBING
J 2
(-5900 3525);
DISPLAY 0.872340 (-5900 3525);
PAINT GREEN (-5900 3525);
DISPLAY INVISIBLE (-5900 3525);
FORCEPROP 1 LAST HDL_TAP TRUE
J 2
(-6225 3350);
DISPLAY 0.872340 (-6225 3350);
DISPLAY INVISIBLE (-6225 3350);
FORCEPROP 1 LAST PATH I292
J 2
(-5898 3475);
DISPLAY 0.872340 (-5898 3475);
PAINT GREEN (-5898 3475);
DISPLAY INVISIBLE (-5898 3475);
FORCEADD TAP..1
R 2
(-5900 3525);
FORCEPROP 3 LASTPIN (-5850 3525) SIG_NAME M_L_CPU1_SA_CA<5>
J 0
(-5840 3535);
DISPLAY 0.659574 (-5840 3535);
PAINT MONO (-5840 3535);
DISPLAY INVISIBLE (-5840 3535);
FORCEPROP 1 LASTPIN (-5850 3525) BN 5
J 2
(-5838 3533);
DISPLAY 0.489362 (-5838 3533);
PAINT GREEN (-5838 3533);
FORCEPROP 2 LAST CDS_LIB mstr_standard
J 0
(-5900 3525);
DISPLAY 0.723404 (-5900 3525);
PAINT MONO (-5900 3525);
DISPLAY INVISIBLE (-5900 3525);
FORCEPROP 1 LAST BODY_TYPE PLUMBING
J 2
(-5900 3575);
DISPLAY 0.872340 (-5900 3575);
PAINT GREEN (-5900 3575);
DISPLAY INVISIBLE (-5900 3575);
FORCEPROP 1 LAST HDL_TAP TRUE
J 2
(-6225 3400);
DISPLAY 0.872340 (-6225 3400);
DISPLAY INVISIBLE (-6225 3400);
FORCEPROP 1 LAST PATH I293
J 2
(-5898 3525);
DISPLAY 0.872340 (-5898 3525);
PAINT GREEN (-5898 3525);
DISPLAY INVISIBLE (-5898 3525);
FORCEADD TAP..1
R 2
(-5900 3575);
FORCEPROP 3 LASTPIN (-5850 3575) SIG_NAME M_L_CPU1_SA_CA<4>
J 0
(-5840 3585);
DISPLAY 0.659574 (-5840 3585);
PAINT MONO (-5840 3585);
DISPLAY INVISIBLE (-5840 3585);
FORCEPROP 1 LASTPIN (-5850 3575) BN 4
J 2
(-5838 3583);
DISPLAY 0.489362 (-5838 3583);
PAINT GREEN (-5838 3583);
FORCEPROP 2 LAST CDS_LIB mstr_standard
J 0
(-5900 3575);
DISPLAY 0.723404 (-5900 3575);
PAINT MONO (-5900 3575);
DISPLAY INVISIBLE (-5900 3575);
FORCEPROP 1 LAST BODY_TYPE PLUMBING
J 2
(-5900 3625);
DISPLAY 0.872340 (-5900 3625);
PAINT GREEN (-5900 3625);
DISPLAY INVISIBLE (-5900 3625);
FORCEPROP 1 LAST HDL_TAP TRUE
J 2
(-6225 3450);
DISPLAY 0.872340 (-6225 3450);
DISPLAY INVISIBLE (-6225 3450);
FORCEPROP 1 LAST PATH I294
J 2
(-5898 3575);
DISPLAY 0.872340 (-5898 3575);
PAINT GREEN (-5898 3575);
DISPLAY INVISIBLE (-5898 3575);
FORCEADD TAP..1
R 2
(-5900 3375);
FORCEPROP 3 LASTPIN (-5850 3375) SIG_NAME M_L_CPU1_SB_CA<0>
J 0
(-5840 3385);
DISPLAY 0.659574 (-5840 3385);
PAINT MONO (-5840 3385);
DISPLAY INVISIBLE (-5840 3385);
FORCEPROP 1 LASTPIN (-5850 3375) BN 0
J 2
(-5838 3383);
DISPLAY 0.489362 (-5838 3383);
PAINT GREEN (-5838 3383);
FORCEPROP 2 LAST CDS_LIB mstr_standard
J 0
(-5900 3375);
DISPLAY 0.723404 (-5900 3375);
PAINT MONO (-5900 3375);
DISPLAY INVISIBLE (-5900 3375);
FORCEPROP 1 LAST BODY_TYPE PLUMBING
J 2
(-5900 3425);
DISPLAY 0.872340 (-5900 3425);
PAINT GREEN (-5900 3425);
DISPLAY INVISIBLE (-5900 3425);
FORCEPROP 1 LAST HDL_TAP TRUE
J 2
(-6225 3250);
DISPLAY 0.872340 (-6225 3250);
DISPLAY INVISIBLE (-6225 3250);
FORCEPROP 1 LAST PATH I295
J 2
(-5898 3375);
DISPLAY 0.872340 (-5898 3375);
PAINT GREEN (-5898 3375);
DISPLAY INVISIBLE (-5898 3375);
FORCEADD TAP..1
R 2
(-5900 3325);
FORCEPROP 3 LASTPIN (-5850 3325) SIG_NAME M_L_CPU1_SB_CA<1>
J 0
(-5840 3335);
DISPLAY 0.659574 (-5840 3335);
PAINT MONO (-5840 3335);
DISPLAY INVISIBLE (-5840 3335);
FORCEPROP 1 LASTPIN (-5850 3325) BN 1
J 2
(-5838 3333);
DISPLAY 0.489362 (-5838 3333);
PAINT GREEN (-5838 3333);
FORCEPROP 2 LAST CDS_LIB mstr_standard
J 0
(-5900 3325);
DISPLAY 0.723404 (-5900 3325);
PAINT MONO (-5900 3325);
DISPLAY INVISIBLE (-5900 3325);
FORCEPROP 1 LAST BODY_TYPE PLUMBING
J 2
(-5900 3375);
DISPLAY 0.872340 (-5900 3375);
PAINT GREEN (-5900 3375);
DISPLAY INVISIBLE (-5900 3375);
FORCEPROP 1 LAST HDL_TAP TRUE
J 2
(-6225 3200);
DISPLAY 0.872340 (-6225 3200);
DISPLAY INVISIBLE (-6225 3200);
FORCEPROP 1 LAST PATH I296
J 2
(-5898 3325);
DISPLAY 0.872340 (-5898 3325);
PAINT GREEN (-5898 3325);
DISPLAY INVISIBLE (-5898 3325);
FORCEADD TAP..1
R 2
(-5900 3225);
FORCEPROP 3 LASTPIN (-5850 3225) SIG_NAME M_L_CPU1_SB_CA<3>
J 0
(-5840 3235);
DISPLAY 0.659574 (-5840 3235);
PAINT MONO (-5840 3235);
DISPLAY INVISIBLE (-5840 3235);
FORCEPROP 1 LASTPIN (-5850 3225) BN 3
J 2
(-5838 3233);
DISPLAY 0.489362 (-5838 3233);
PAINT GREEN (-5838 3233);
FORCEPROP 2 LAST CDS_LIB mstr_standard
J 0
(-5900 3225);
DISPLAY 0.723404 (-5900 3225);
PAINT MONO (-5900 3225);
DISPLAY INVISIBLE (-5900 3225);
FORCEPROP 1 LAST BODY_TYPE PLUMBING
J 2
(-5900 3275);
DISPLAY 0.872340 (-5900 3275);
PAINT GREEN (-5900 3275);
DISPLAY INVISIBLE (-5900 3275);
FORCEPROP 1 LAST HDL_TAP TRUE
J 2
(-6225 3100);
DISPLAY 0.872340 (-6225 3100);
DISPLAY INVISIBLE (-6225 3100);
FORCEPROP 1 LAST PATH I297
J 2
(-5898 3225);
DISPLAY 0.872340 (-5898 3225);
PAINT GREEN (-5898 3225);
DISPLAY INVISIBLE (-5898 3225);
FORCEADD TAP..1
R 2
(-5900 3275);
FORCEPROP 3 LASTPIN (-5850 3275) SIG_NAME M_L_CPU1_SB_CA<2>
J 0
(-5840 3285);
DISPLAY 0.659574 (-5840 3285);
PAINT MONO (-5840 3285);
DISPLAY INVISIBLE (-5840 3285);
FORCEPROP 1 LASTPIN (-5850 3275) BN 2
J 2
(-5838 3283);
DISPLAY 0.489362 (-5838 3283);
PAINT GREEN (-5838 3283);
FORCEPROP 2 LAST CDS_LIB mstr_standard
J 0
(-5900 3275);
DISPLAY 0.723404 (-5900 3275);
PAINT MONO (-5900 3275);
DISPLAY INVISIBLE (-5900 3275);
FORCEPROP 1 LAST BODY_TYPE PLUMBING
J 2
(-5900 3325);
DISPLAY 0.872340 (-5900 3325);
PAINT GREEN (-5900 3325);
DISPLAY INVISIBLE (-5900 3325);
FORCEPROP 1 LAST HDL_TAP TRUE
J 2
(-6225 3150);
DISPLAY 0.872340 (-6225 3150);
DISPLAY INVISIBLE (-6225 3150);
FORCEPROP 1 LAST PATH I298
J 2
(-5898 3275);
DISPLAY 0.872340 (-5898 3275);
PAINT GREEN (-5898 3275);
DISPLAY INVISIBLE (-5898 3275);
FORCEADD TAP..1
R 2
(-5900 3075);
FORCEPROP 3 LASTPIN (-5850 3075) SIG_NAME M_L_CPU1_SB_CA<6>
J 0
(-5840 3085);
DISPLAY 0.659574 (-5840 3085);
PAINT MONO (-5840 3085);
DISPLAY INVISIBLE (-5840 3085);
FORCEPROP 1 LASTPIN (-5850 3075) BN 6
J 2
(-5838 3083);
DISPLAY 0.489362 (-5838 3083);
PAINT GREEN (-5838 3083);
FORCEPROP 2 LAST CDS_LIB mstr_standard
J 0
(-5900 3075);
DISPLAY 0.723404 (-5900 3075);
PAINT MONO (-5900 3075);
DISPLAY INVISIBLE (-5900 3075);
FORCEPROP 1 LAST BODY_TYPE PLUMBING
J 2
(-5900 3125);
DISPLAY 0.872340 (-5900 3125);
PAINT GREEN (-5900 3125);
DISPLAY INVISIBLE (-5900 3125);
FORCEPROP 1 LAST HDL_TAP TRUE
J 2
(-6225 2950);
DISPLAY 0.872340 (-6225 2950);
DISPLAY INVISIBLE (-6225 2950);
FORCEPROP 1 LAST PATH I299
J 2
(-5898 3075);
DISPLAY 0.872340 (-5898 3075);
PAINT GREEN (-5898 3075);
DISPLAY INVISIBLE (-5898 3075);
FORCEADD TAP..1
R 2
(-5900 3125);
FORCEPROP 3 LASTPIN (-5850 3125) SIG_NAME M_L_CPU1_SB_CA<5>
J 0
(-5840 3135);
DISPLAY 0.659574 (-5840 3135);
PAINT MONO (-5840 3135);
DISPLAY INVISIBLE (-5840 3135);
FORCEPROP 1 LASTPIN (-5850 3125) BN 5
J 2
(-5838 3133);
DISPLAY 0.489362 (-5838 3133);
PAINT GREEN (-5838 3133);
FORCEPROP 2 LAST CDS_LIB mstr_standard
J 0
(-5900 3125);
DISPLAY 0.723404 (-5900 3125);
PAINT MONO (-5900 3125);
DISPLAY INVISIBLE (-5900 3125);
FORCEPROP 1 LAST BODY_TYPE PLUMBING
J 2
(-5900 3175);
DISPLAY 0.872340 (-5900 3175);
PAINT GREEN (-5900 3175);
DISPLAY INVISIBLE (-5900 3175);
FORCEPROP 1 LAST HDL_TAP TRUE
J 2
(-6225 3000);
DISPLAY 0.872340 (-6225 3000);
DISPLAY INVISIBLE (-6225 3000);
FORCEPROP 1 LAST PATH I300
J 2
(-5898 3125);
DISPLAY 0.872340 (-5898 3125);
PAINT GREEN (-5898 3125);
DISPLAY INVISIBLE (-5898 3125);
FORCEADD TAP..1
R 2
(-5900 3175);
FORCEPROP 3 LASTPIN (-5850 3175) SIG_NAME M_L_CPU1_SB_CA<4>
J 0
(-5840 3185);
DISPLAY 0.659574 (-5840 3185);
PAINT MONO (-5840 3185);
DISPLAY INVISIBLE (-5840 3185);
FORCEPROP 1 LASTPIN (-5850 3175) BN 4
J 2
(-5838 3183);
DISPLAY 0.489362 (-5838 3183);
PAINT GREEN (-5838 3183);
FORCEPROP 2 LAST CDS_LIB mstr_standard
J 0
(-5900 3175);
DISPLAY 0.723404 (-5900 3175);
PAINT MONO (-5900 3175);
DISPLAY INVISIBLE (-5900 3175);
FORCEPROP 1 LAST BODY_TYPE PLUMBING
J 2
(-5900 3225);
DISPLAY 0.872340 (-5900 3225);
PAINT GREEN (-5900 3225);
DISPLAY INVISIBLE (-5900 3225);
FORCEPROP 1 LAST HDL_TAP TRUE
J 2
(-6225 3050);
DISPLAY 0.872340 (-6225 3050);
DISPLAY INVISIBLE (-6225 3050);
FORCEPROP 1 LAST PATH I301
J 2
(-5898 3175);
DISPLAY 0.872340 (-5898 3175);
PAINT GREEN (-5898 3175);
DISPLAY INVISIBLE (-5898 3175);
FORCEADD OFFPAGE..2
R 2
(-6500 3800);
FORCEPROP 2 LAST $XR0 108 
J 0
(-6785 3800);
DISPLAY 0.638298 (-6785 3800);
PAINT MONO (-6785 3800);
FORCEPROP 2 LAST PATH I302
J 0
(-6775 3850);
DISPLAY 1.021277 (-6775 3850);
DISPLAY INVISIBLE (-6775 3850);
FORCEPROP 1 LAST COMMENT_BODY TRUE
J 2
(-6455 3705);
DISPLAY 0.872340 (-6455 3705);
PAINT GREEN (-6455 3705);
DISPLAY INVISIBLE (-6455 3705);
FORCEPROP 1 LAST OFFPAGE TRUE
J 2
(-6825 3675);
DISPLAY 0.872340 (-6825 3675);
PAINT GREEN (-6825 3675);
DISPLAY INVISIBLE (-6825 3675);
FORCEPROP 2 LAST CDS_LIB standard
J 0
(-6500 3800);
DISPLAY INVISIBLE (-6500 3800);
FORCEADD OFFPAGE..2
R 2
(-6500 3400);
FORCEPROP 2 LAST $XR0 108 
J 0
(-6785 3400);
DISPLAY 0.638298 (-6785 3400);
PAINT MONO (-6785 3400);
FORCEPROP 2 LAST PATH I303
J 0
(-6775 3450);
DISPLAY 1.021277 (-6775 3450);
DISPLAY INVISIBLE (-6775 3450);
FORCEPROP 1 LAST COMMENT_BODY TRUE
J 2
(-6455 3305);
DISPLAY 0.872340 (-6455 3305);
PAINT GREEN (-6455 3305);
DISPLAY INVISIBLE (-6455 3305);
FORCEPROP 1 LAST OFFPAGE TRUE
J 2
(-6825 3275);
DISPLAY 0.872340 (-6825 3275);
PAINT GREEN (-6825 3275);
DISPLAY INVISIBLE (-6825 3275);
FORCEPROP 2 LAST CDS_LIB standard
J 0
(-6500 3400);
DISPLAY INVISIBLE (-6500 3400);
FORCEADD OFFPAGE..2
R 2
(-6500 2925);
FORCEPROP 2 LAST $XR0 108 
J 0
(-6785 2925);
DISPLAY 0.638298 (-6785 2925);
PAINT MONO (-6785 2925);
FORCEPROP 2 LAST PATH I304
J 0
(-6775 2975);
DISPLAY 1.021277 (-6775 2975);
DISPLAY INVISIBLE (-6775 2975);
FORCEPROP 1 LAST COMMENT_BODY TRUE
J 2
(-6455 2830);
DISPLAY 0.872340 (-6455 2830);
PAINT GREEN (-6455 2830);
DISPLAY INVISIBLE (-6455 2830);
FORCEPROP 1 LAST OFFPAGE TRUE
J 2
(-6825 2800);
DISPLAY 0.872340 (-6825 2800);
PAINT GREEN (-6825 2800);
DISPLAY INVISIBLE (-6825 2800);
FORCEPROP 2 LAST CDS_LIB standard
J 0
(-6500 2925);
DISPLAY INVISIBLE (-6500 2925);
FORCEADD OFFPAGE..2
R 2
(-6500 2875);
FORCEPROP 2 LAST $XR0 108 
J 0
(-6785 2875);
DISPLAY 0.638298 (-6785 2875);
PAINT MONO (-6785 2875);
FORCEPROP 2 LAST PATH I305
J 0
(-6775 2925);
DISPLAY 1.021277 (-6775 2925);
DISPLAY INVISIBLE (-6775 2925);
FORCEPROP 1 LAST COMMENT_BODY TRUE
J 2
(-6455 2780);
DISPLAY 0.872340 (-6455 2780);
PAINT GREEN (-6455 2780);
DISPLAY INVISIBLE (-6455 2780);
FORCEPROP 1 LAST OFFPAGE TRUE
J 2
(-6825 2750);
DISPLAY 0.872340 (-6825 2750);
PAINT GREEN (-6825 2750);
DISPLAY INVISIBLE (-6825 2750);
FORCEPROP 2 LAST CDS_LIB standard
J 0
(-6500 2875);
DISPLAY INVISIBLE (-6500 2875);
FORCEADD OFFPAGE..2
R 2
(-6500 2775);
FORCEPROP 2 LAST $XR0 108 
J 0
(-6785 2775);
DISPLAY 0.638298 (-6785 2775);
PAINT MONO (-6785 2775);
FORCEPROP 2 LAST PATH I306
J 0
(-6775 2825);
DISPLAY 1.021277 (-6775 2825);
DISPLAY INVISIBLE (-6775 2825);
FORCEPROP 1 LAST COMMENT_BODY TRUE
J 2
(-6455 2680);
DISPLAY 0.872340 (-6455 2680);
PAINT GREEN (-6455 2680);
DISPLAY INVISIBLE (-6455 2680);
FORCEPROP 1 LAST OFFPAGE TRUE
J 2
(-6825 2650);
DISPLAY 0.872340 (-6825 2650);
PAINT GREEN (-6825 2650);
DISPLAY INVISIBLE (-6825 2650);
FORCEPROP 2 LAST CDS_LIB standard
J 0
(-6500 2775);
DISPLAY INVISIBLE (-6500 2775);
FORCEADD OFFPAGE..2
R 2
(-6500 2725);
FORCEPROP 2 LAST $XR0 108 
J 0
(-6785 2725);
DISPLAY 0.638298 (-6785 2725);
PAINT MONO (-6785 2725);
FORCEPROP 2 LAST PATH I307
J 0
(-6775 2775);
DISPLAY 1.021277 (-6775 2775);
DISPLAY INVISIBLE (-6775 2775);
FORCEPROP 1 LAST COMMENT_BODY TRUE
J 2
(-6455 2630);
DISPLAY 0.872340 (-6455 2630);
PAINT GREEN (-6455 2630);
DISPLAY INVISIBLE (-6455 2630);
FORCEPROP 1 LAST OFFPAGE TRUE
J 2
(-6825 2600);
DISPLAY 0.872340 (-6825 2600);
PAINT GREEN (-6825 2600);
DISPLAY INVISIBLE (-6825 2600);
FORCEPROP 2 LAST CDS_LIB standard
J 0
(-6500 2725);
DISPLAY INVISIBLE (-6500 2725);
FORCEADD OFFPAGE..1
(-6500 2625);
FORCEPROP 2 LAST $XR0 108 
J 0
(-6752 2625);
DISPLAY 0.638298 (-6752 2625);
PAINT MONO (-6752 2625);
FORCEPROP 2 LAST PATH I308
J 0
(-6750 2675);
DISPLAY 1.021277 (-6750 2675);
DISPLAY INVISIBLE (-6750 2675);
FORCEPROP 1 LAST COMMENT_BODY TRUE
J 0
(-6375 2525);
DISPLAY 0.872340 (-6375 2525);
PAINT GREEN (-6375 2525);
DISPLAY INVISIBLE (-6375 2525);
FORCEPROP 1 LAST OFFPAGE TRUE
J 0
(-6175 2500);
DISPLAY 0.872340 (-6175 2500);
PAINT GREEN (-6175 2500);
DISPLAY INVISIBLE (-6175 2500);
FORCEPROP 2 LAST CDS_LIB standard
J 0
(-6500 2625);
DISPLAY INVISIBLE (-6500 2625);
FORCEADD OFFPAGE..5
(-6500 2525);
FORCEPROP 2 LAST $XR0 108 
J 0
(-6785 2525);
DISPLAY 0.638298 (-6785 2525);
PAINT MONO (-6785 2525);
FORCEPROP 2 LAST PATH I309
J 0
(-6775 2575);
DISPLAY 1.021277 (-6775 2575);
DISPLAY INVISIBLE (-6775 2575);
FORCEPROP 1 LAST COMMENT_BODY TRUE
J 0
(-6400 2450);
DISPLAY 0.872340 (-6400 2450);
PAINT GREEN (-6400 2450);
DISPLAY INVISIBLE (-6400 2450);
FORCEPROP 1 LAST OFFPAGE TRUE
J 0
(-6175 2400);
DISPLAY 0.872340 (-6175 2400);
PAINT GREEN (-6175 2400);
DISPLAY INVISIBLE (-6175 2400);
FORCEPROP 2 LAST CDS_LIB mstr_standard
J 0
(-6500 2525);
DISPLAY INVISIBLE (-6500 2525);
FORCEADD OFFPAGE..2
R 2
(-6500 2375);
FORCEPROP 2 LAST $XR0 108 
J 0
(-6785 2375);
DISPLAY 0.638298 (-6785 2375);
PAINT MONO (-6785 2375);
FORCEPROP 2 LAST PATH I310
J 0
(-6775 2425);
DISPLAY 1.021277 (-6775 2425);
DISPLAY INVISIBLE (-6775 2425);
FORCEPROP 1 LAST COMMENT_BODY TRUE
J 2
(-6455 2280);
DISPLAY 0.872340 (-6455 2280);
PAINT GREEN (-6455 2280);
DISPLAY INVISIBLE (-6455 2280);
FORCEPROP 1 LAST OFFPAGE TRUE
J 2
(-6825 2250);
DISPLAY 0.872340 (-6825 2250);
PAINT GREEN (-6825 2250);
DISPLAY INVISIBLE (-6825 2250);
FORCEPROP 2 LAST CDS_LIB standard
J 0
(-6500 2375);
DISPLAY INVISIBLE (-6500 2375);
FORCEADD OFFPAGE..2
R 2
(-6500 2425);
FORCEPROP 2 LAST $XR0 108 
J 0
(-6785 2425);
DISPLAY 0.638298 (-6785 2425);
PAINT MONO (-6785 2425);
FORCEPROP 2 LAST PATH I311
J 0
(-6775 2475);
DISPLAY 1.021277 (-6775 2475);
DISPLAY INVISIBLE (-6775 2475);
FORCEPROP 1 LAST COMMENT_BODY TRUE
J 2
(-6455 2330);
DISPLAY 0.872340 (-6455 2330);
PAINT GREEN (-6455 2330);
DISPLAY INVISIBLE (-6455 2330);
FORCEPROP 1 LAST OFFPAGE TRUE
J 2
(-6825 2300);
DISPLAY 0.872340 (-6825 2300);
PAINT GREEN (-6825 2300);
DISPLAY INVISIBLE (-6825 2300);
FORCEPROP 2 LAST CDS_LIB standard
J 0
(-6500 2425);
DISPLAY INVISIBLE (-6500 2425);
FORCEADD OFFPAGE..5
(-6500 2175);
FORCEPROP 2 LAST $XR0 108 
J 0
(-6785 2175);
DISPLAY 0.638298 (-6785 2175);
PAINT MONO (-6785 2175);
FORCEPROP 2 LAST PATH I312
J 0
(-6775 2225);
DISPLAY 1.021277 (-6775 2225);
DISPLAY INVISIBLE (-6775 2225);
FORCEPROP 1 LAST COMMENT_BODY TRUE
J 0
(-6400 2100);
DISPLAY 0.872340 (-6400 2100);
PAINT GREEN (-6400 2100);
DISPLAY INVISIBLE (-6400 2100);
FORCEPROP 1 LAST OFFPAGE TRUE
J 0
(-6175 2050);
DISPLAY 0.872340 (-6175 2050);
PAINT GREEN (-6175 2050);
DISPLAY INVISIBLE (-6175 2050);
FORCEPROP 2 LAST CDS_LIB standard
J 0
(-6500 2175);
DISPLAY INVISIBLE (-6500 2175);
FORCEADD Q_RES..1
(-6575 2075);
FORCEPROP 1 LAST LOCATION R511
J 0
(-6900 2075);
DISPLAY 0.489362 (-6900 2075);
PAINT SKYBLUE (-6900 2075);
FORCEPROP 0 LAST $SEC 1
J 0
(-6750 2125);
DISPLAY 0.680851 (-6750 2125);
PAINT MONO (-6750 2125);
DISPLAY INVISIBLE (-6750 2125);
FORCEPROP 0 LAST CDS_SEC 1
J 0
(-6750 2125);
DISPLAY 1.021277 (-6750 2125);
DISPLAY INVISIBLE (-6750 2125);
FORCEPROP 1 LASTPIN (-6675 2075) $PN 1
J 0
(-6663 2087);
DISPLAY 0.489362 (-6663 2087);
PAINT MONO (-6663 2087);
FORCEPROP 1 LASTPIN (-6475 2075) $PN 2
J 0
(-6513 2087);
DISPLAY 0.489362 (-6513 2087);
PAINT MONO (-6513 2087);
FORCEPROP 1 LAST TOLERANCE 1%
J 0
(-6300 2075);
DISPLAY 0.489362 (-6300 2075);
PAINT SKYBLUE (-6300 2075);
FORCEPROP 1 LAST VALUE 15   
J 2
(-6250 2075);
DISPLAY 0.489362 (-6250 2075);
PAINT SKYBLUE (-6250 2075);
FORCEPROP 1 LAST PART_NUMBER CS01502FB11
J 0
(-6450 2050);
DISPLAY 0.489362 (-6450 2050);
PAINT SKYBLUE (-6450 2050);
FORCEPROP 1 LAST PACK_TYPE 0402LF
J 0
(-6900 2050);
DISPLAY 0.489362 (-6900 2050);
PAINT SKYBLUE (-6900 2050);
FORCEPROP 2 LAST CDS_LIB pure_quanta
J 0
(-6575 2075);
DISPLAY INVISIBLE (-6575 2075);
FORCEPROP 1 LAST PATH I313
J 0
(-6625 2225);
DISPLAY 0.978723 (-6625 2225);
PAINT WHITE (-6625 2225);
DISPLAY INVISIBLE (-6625 2225);
FORCEPROP 1 LAST WATTAGE 1/16W
J 2
(-6350 2200);
DISPLAY 0.638298 (-6350 2200);
PAINT SKYBLUE (-6350 2200);
DISPLAY INVISIBLE (-6350 2200);
FORCEPROP 1 LAST MATERIAL CHIP
J 0
(-6700 2200);
DISPLAY 0.638298 (-6700 2200);
PAINT SKYBLUE (-6700 2200);
DISPLAY INVISIBLE (-6700 2200);
FORCEADD OFFPAGE..1
(-6500 2275);
FORCEPROP 2 LAST $XR0 108 
J 0
(-6752 2275);
DISPLAY 0.638298 (-6752 2275);
PAINT MONO (-6752 2275);
FORCEPROP 2 LAST PATH I314
J 0
(-6750 2325);
DISPLAY 1.021277 (-6750 2325);
DISPLAY INVISIBLE (-6750 2325);
FORCEPROP 1 LAST COMMENT_BODY TRUE
J 0
(-6375 2175);
DISPLAY 0.872340 (-6375 2175);
PAINT GREEN (-6375 2175);
DISPLAY INVISIBLE (-6375 2175);
FORCEPROP 1 LAST OFFPAGE TRUE
J 0
(-6175 2150);
DISPLAY 0.872340 (-6175 2150);
PAINT GREEN (-6175 2150);
DISPLAY INVISIBLE (-6175 2150);
FORCEPROP 2 LAST CDS_LIB standard
J 0
(-6500 2275);
DISPLAY INVISIBLE (-6500 2275);
FORCEADD OFFPAGE..5
(-6500 1975);
FORCEPROP 2 LAST $XR0 108 
J 0
(-6785 1975);
DISPLAY 0.638298 (-6785 1975);
PAINT MONO (-6785 1975);
FORCEPROP 2 LAST PATH I315
J 0
(-6775 2025);
DISPLAY 1.021277 (-6775 2025);
DISPLAY INVISIBLE (-6775 2025);
FORCEPROP 1 LAST COMMENT_BODY TRUE
J 0
(-6400 1900);
DISPLAY 0.872340 (-6400 1900);
PAINT GREEN (-6400 1900);
DISPLAY INVISIBLE (-6400 1900);
FORCEPROP 1 LAST OFFPAGE TRUE
J 0
(-6175 1850);
DISPLAY 0.872340 (-6175 1850);
PAINT GREEN (-6175 1850);
DISPLAY INVISIBLE (-6175 1850);
FORCEPROP 2 LAST CDS_LIB standard
J 0
(-6500 1975);
DISPLAY INVISIBLE (-6500 1975);
FORCEADD OFFPAGE..1
(-7450 2075);
FORCEPROP 2 LAST $XR0 108 
J 0
(-7702 2075);
DISPLAY 0.638298 (-7702 2075);
PAINT MONO (-7702 2075);
FORCEPROP 2 LAST PATH I316
J 0
(-7725 2125);
DISPLAY 1.021277 (-7725 2125);
DISPLAY INVISIBLE (-7725 2125);
FORCEPROP 1 LAST COMMENT_BODY TRUE
J 0
(-7325 1975);
DISPLAY 0.872340 (-7325 1975);
PAINT GREEN (-7325 1975);
DISPLAY INVISIBLE (-7325 1975);
FORCEPROP 1 LAST OFFPAGE TRUE
J 0
(-7125 1950);
DISPLAY 0.872340 (-7125 1950);
PAINT GREEN (-7125 1950);
DISPLAY INVISIBLE (-7125 1950);
FORCEPROP 2 LAST CDS_LIB mstr_standard
J 0
(-7450 2075);
DISPLAY INVISIBLE (-7450 2075);
FORCEADD CAD_NOTE..1
(-7650 2350);
FORCEPROP 0 LAST L1 R1957 PLACE CLOSE TO CPU < 25MM
J 0
(-7800 2225);
DISPLAY 0.617021 (-7800 2225);
PAINT WHITE (-7800 2225);
FORCEPROP 2 LAST CDS_LIB pure_quanta_power
J 0
(-7650 2350);
DISPLAY INVISIBLE (-7650 2350);
FORCEPROP 1 LAST COMMENT_BODY TRUE
J 0
(-7625 2450);
DISPLAY 0.574468 (-7625 2450);
PAINT WHITE (-7625 2450);
DISPLAY INVISIBLE (-7625 2450);
FORCEADD QUANTA_TITLE_BLOCK_C..1
(0 0);
FORCEPROP 0 LAST CDS_CON_LAST_MODIFIED Fri Mar 11 14:52:35 2022
J 0
(-1885 15);
DISPLAY INVISIBLE (-1885 15);
FORCEPROP 1 LAST CUSTOM_TXT_CDS <CON_LAST_MODIFIED>
J 0
(-1885 15);
DISPLAY 0.978723 (-1885 15);
FORCEPROP 2 LAST CUSTOM_TXT_CDS <XR_PAGE_TITLE>
J 0
(-7890 5250);
DISPLAY 0.638298 (-7890 5250);
PAINT PINK (-7890 5250);
DISPLAY INVISIBLE (-7890 5250);
FORCEPROP 1 LAST CUSTOM_TXT_CDS <NAME_2>
J 0
(-3175 50);
FORCEPROP 1 LAST CUSTOM_TXT_CDS <NAME_1>
J 0
(-3175 175);
FORCEPROP 1 LAST CUSTOM_TXT_CDS <Q_NUMBER>
J 0
(-1403 103);
DISPLAY 1.212766 (-1403 103);
FORCEPROP 1 LAST CUSTOM_TXT_CDS <Q_PROJ>
J 0
(-2382 102);
DISPLAY 1.212766 (-2382 102);
FORCEPROP 1 LAST CUSTOM_TXT_CDS <Q_REV>
J 0
(-184 103);
DISPLAY 1.212766 (-184 103);
FORCEPROP 1 LAST CUSTOM_TXT_CDS <CON_PAGE_NUM> OF <CON_TOTAL_PAGES>
J 0
(-446 18);
DISPLAY 0.978723 (-446 18);
FORCEPROP 1 LAST Q_TITLE CPU1 DDR CHL
J 0
(-9366 26);
DISPLAY 2.446809 (-9366 26);
PAINT GREEN (-9366 26);
FORCEPROP 1 LAST Q_DEPT BU9
J 1
(-3763 49);
DISPLAY 1.957447 (-3763 49);
PAINT GREEN (-3763 49);
FORCEPROP 2 LAST PAGE_BORDER TRUE
J 0
(-7890 5250);
DISPLAY 0.638298 (-7890 5250);
PAINT PINK (-7890 5250);
DISPLAY INVISIBLE (-7890 5250);
FORCEPROP 1 LAST CDS_LMAN_SYM_OUTLINE -9475,6775,100,-125
J 0
(0 0);
DISPLAY 0.468085 (0 0);
PAINT GREEN (0 0);
DISPLAY INVISIBLE (0 0);
FORCEPROP 2 LAST CDS_LIB pure_quanta
J 0
(0 0);
DISPLAY INVISIBLE (0 0);
FORCEPROP 1 LAST COMMENT_BODY TRUE
J 0
(12 -13);
DISPLAY 0.978723 (12 -13);
PAINT GREEN (12 -13);
DISPLAY INVISIBLE (12 -13);
FORCEPROP 2 LAST CDS_XR_PAGE_TITLE CR-48 : @T6G_MB_LIB.T6G(SCH_1):PAGE48
J 0
(-7890 5250);
DISPLAY 0.638298 (-7890 5250);
PAINT PINK (-7890 5250);
DISPLAY INVISIBLE (-7890 5250);
WIRE 17 -1 (-3225 5350)(-3225 5300);
WIRE 17 -1 (-3225 5400)(-3225 5350);
WIRE 17 -1 (-3225 5300)(-3225 5250);
WIRE 17 -1 (-3225 5250)(-3225 5200);
WIRE 17 -1 (-3225 5450)(-3225 5400);
WIRE 17 -1 (-3225 5500)(-3225 5450);
WIRE 17 -1 (-3225 5200)(-3225 5150);
WIRE 17 -1 (-3225 5050)(-3225 5150);
WIRE 17 -1 (-3225 5600)(-3225 5500);
WIRE 17 -1 (-3225 5650)(-3225 5600);
WIRE 17 -1 (-3225 5000)(-3225 5050);
WIRE 17 -1 (-3225 4950)(-3225 5000);
WIRE 17 -1 (-3225 5700)(-3225 5650);
WIRE 17 -1 (-3225 5750)(-3225 5700);
WIRE 17 -1 (-3225 4900)(-3225 4950);
WIRE 17 -1 (-3225 4900)(-3225 4850);
WIRE 17 -1 (-3225 5800)(-3225 5750);
WIRE 17 -1 (-3225 5850)(-3225 5800);
WIRE 17 -1 (-3225 4850)(-3225 4800);
WIRE 17 -1 (-3225 4800)(-3225 4750);
WIRE 17 -1 (-3225 5900)(-3225 5850);
WIRE 17 -1 (-3225 5950)(-3225 5900);
WIRE 17 -1 (-3225 4750)(-3225 4700);
WIRE 17 -1 (-3225 4700)(-3225 4600);
WIRE 17 -1 (-3225 5950)(-2600 5950);
FORCEPROP 2 LAST SIG_NAME M_L_CPU1_SA_DQ<31:0>
J 2
(-2660 5960);
DISPLAY 0.489362 (-2660 5960);
WIRE 17 -1 (-3225 4600)(-3225 4550);
WIRE 17 -1 (-3225 4550)(-3225 4500);
WIRE 17 -1 (-3225 4500)(-3225 4450);
WIRE 17 -1 (-3225 4400)(-3225 4450);
WIRE 17 -1 (-3225 4350)(-3225 4400);
WIRE 17 -1 (-3225 4300)(-3225 4350);
WIRE 17 -1 (-3225 4250)(-3225 4300);
WIRE 17 -1 (-3225 4150)(-2600 4150);
FORCEPROP 2 LAST SIG_NAME M_L_CPU1_SB_DQ<31:0>
J 2
(-2660 4160);
DISPLAY 0.489362 (-2660 4160);
WIRE 17 -1 (-3225 3950)(-3225 3900);
WIRE 17 -1 (-3225 4000)(-3225 3950);
WIRE 17 -1 (-3225 3900)(-3225 3850);
WIRE 17 -1 (-3225 3850)(-3225 3800);
WIRE 17 -1 (-3225 4050)(-3225 4000);
WIRE 17 -1 (-3225 4100)(-3225 4050);
WIRE 17 -1 (-3225 3800)(-3225 3700);
WIRE 17 -1 (-3225 3700)(-3225 3650);
WIRE 17 -1 (-3225 4150)(-3225 4100);
WIRE 17 -1 (-3225 3650)(-3225 3600);
WIRE 17 -1 (-3225 3600)(-3225 3550);
WIRE 17 -1 (-3225 3550)(-3225 3500);
WIRE 17 -1 (-3225 3500)(-3225 3450);
WIRE 17 -1 (-3225 3450)(-3225 3400);
WIRE 17 -1 (-3225 3400)(-3225 3350);
WIRE 17 -1 (-3225 3250)(-3225 3350);
WIRE 17 -1 (-3225 3200)(-3225 3250);
WIRE 17 -1 (-3225 3150)(-3225 3200);
WIRE 17 -1 (-3225 3100)(-3225 3150);
WIRE 17 -1 (-3225 3100)(-3225 3050);
WIRE 17 -1 (-3225 3050)(-3225 3000);
WIRE 17 -1 (-3225 3000)(-3225 2950);
WIRE 17 -1 (-3225 2950)(-3225 2900);
WIRE 17 -1 (-3225 2900)(-3225 2800);
WIRE 17 -1 (-3225 2800)(-3225 2750);
WIRE 17 -1 (-3225 2750)(-3225 2700);
WIRE 17 -1 (-3225 2700)(-3225 2650);
WIRE 17 -1 (-3225 2600)(-3225 2650);
WIRE 17 -1 (-3225 2550)(-3225 2600);
WIRE 17 -1 (-3225 2500)(-3225 2550);
WIRE 17 -1 (-3225 2450)(-3225 2500);
WIRE 17 -1 (-3225 2250)(-3225 2300);
WIRE 17 -1 (-3225 2250)(-3225 2200);
WIRE 17 -1 (-3225 2350)(-3225 2300);
WIRE 17 -1 (-3225 2350)(-3225 2375);
WIRE 17 -1 (-3225 2150)(-3225 2200);
WIRE 17 -1 (-3225 2100)(-3225 2150);
WIRE 17 -1 (-3225 2375)(-2725 2375);
FORCEPROP 2 LAST SIG_NAME M_L_CPU1_SA_CB<7:0>
J 2
(-2725 2385);
DISPLAY 0.489362 (-2725 2385);
WIRE 17 -1 (-3225 2050)(-3225 2100);
WIRE 17 -1 (-3225 2000)(-3225 2050);
WIRE 17 -1 (-3225 1900)(-3225 1850);
WIRE 17 -1 (-3225 1900)(-3225 1925);
WIRE 17 -1 (-3225 1800)(-3225 1850);
WIRE 17 -1 (-3225 1800)(-3225 1750);
WIRE 17 -1 (-3225 1925)(-2725 1925);
FORCEPROP 2 LAST SIG_NAME M_L_CPU1_SB_CB<7:0>
J 2
(-2725 1935);
DISPLAY 0.489362 (-2725 1935);
WIRE 17 -1 (-3225 1700)(-3225 1750);
WIRE 17 -1 (-3225 1650)(-3225 1700);
WIRE 17 -1 (-3225 1600)(-3225 1650);
WIRE 17 -1 (-3225 1550)(-3225 1600);
WIRE 17 -1 (-5950 5900)(-5950 5800);
FORCEPROP 2 LAST SIG_NAME M_L_CPU1_SA_DQS_DN<9:0>
J 2
(-5985 5910);
DISPLAY 0.489362 (-5985 5910);
WIRE 17 -1 (-5950 5700)(-5950 5600);
WIRE 17 -1 (-5950 5800)(-5950 5700);
WIRE 17 -1 (-5950 5600)(-5950 5500);
WIRE 17 -1 (-5950 5400)(-5950 5500);
WIRE 17 -1 (-5950 5300)(-5950 5400);
WIRE 17 -1 (-5950 5200)(-5950 5300);
WIRE 17 -1 (-5950 5200)(-5950 5100);
WIRE 17 -1 (-5750 5950)(-5750 5850);
WIRE 17 -1 (-5750 5950)(-6550 5950);
FORCEPROP 2 LAST SIG_NAME M_L_CPU1_SA_DQS_DP<9:0>
J 2
(-5985 5960);
DISPLAY 0.489362 (-5985 5960);
WIRE 17 -1 (-5950 5100)(-5950 5000);
WIRE 17 -1 (-5750 5850)(-5750 5750);
WIRE 17 -1 (-5750 5750)(-5750 5650);
WIRE 17 -1 (-5750 5650)(-5750 5550);
WIRE 17 -1 (-5750 5450)(-5750 5550);
WIRE 17 -1 (-5750 5350)(-5750 5450);
WIRE 17 -1 (-5750 5250)(-5750 5350);
WIRE 17 -1 (-5750 5250)(-5750 5150);
WIRE 17 -1 (-5750 5150)(-5750 5050);
WIRE 17 -1 (-5750 4400)(-5750 4500);
WIRE 17 -1 (-5750 4300)(-5750 4400);
WIRE 17 -1 (-5750 4600)(-5750 4500);
WIRE 17 -1 (-5750 4700)(-5750 4600);
WIRE 17 -1 (-5750 4200)(-5750 4300);
WIRE 17 -1 (-5750 4200)(-5750 4100);
WIRE 17 -1 (-5750 4800)(-5750 4700);
WIRE 17 -1 (-5750 4900)(-5750 4800);
WIRE 17 -1 (-5750 4100)(-5750 4000);
WIRE 17 -1 (-5750 4900)(-6550 4900);
FORCEPROP 2 LAST SIG_NAME M_L_CPU1_SB_DQS_DP<9:0>
J 2
(-5985 4910);
DISPLAY 0.489362 (-5985 4910);
WIRE 17 -1 (-5950 4850)(-5950 4750);
FORCEPROP 2 LAST SIG_NAME M_L_CPU1_SB_DQS_DN<9:0>
J 2
(-5985 4860);
DISPLAY 0.489362 (-5985 4860);
WIRE 17 -1 (-5950 4650)(-5950 4550);
WIRE 17 -1 (-5950 4750)(-5950 4650);
WIRE 17 -1 (-5950 4550)(-5950 4450);
WIRE 17 -1 (-5950 4350)(-5950 4450);
WIRE 17 -1 (-5950 4250)(-5950 4350);
WIRE 17 -1 (-5950 4150)(-5950 4250);
WIRE 17 -1 (-5950 4150)(-5950 4050);
WIRE 17 -1 (-5950 4050)(-5950 3950);
WIRE 17 -1 (-5950 3350)(-5950 3400);
WIRE 17 -1 (-5950 3300)(-5950 3350);
WIRE 17 -1 (-5950 3400)(-6450 3400);
FORCEPROP 2 LAST SIG_NAME M_L_CPU1_SB_CA<6:0>
J 0
(-6450 3410);
DISPLAY 0.489362 (-6450 3410);
WIRE 17 -1 (-5950 3700)(-5950 3750);
WIRE 17 -1 (-5950 3650)(-5950 3700);
WIRE 17 -1 (-5950 3750)(-5950 3800);
WIRE 17 -1 (-5950 3800)(-6450 3800);
FORCEPROP 2 LAST SIG_NAME M_L_CPU1_SA_CA<6:0>
J 0
(-6450 3810);
DISPLAY 0.489362 (-6450 3810);
WIRE 17 -1 (-5950 3250)(-5950 3300);
WIRE 17 -1 (-5950 3200)(-5950 3250);
WIRE 17 -1 (-5950 3150)(-5950 3200);
WIRE 17 -1 (-5950 3100)(-5950 3150);
WIRE 17 -1 (-5950 3600)(-5950 3650);
WIRE 17 -1 (-5950 3550)(-5950 3600);
WIRE 17 -1 (-5950 3500)(-5950 3550);
WIRE 17 -1 (-5950 5900)(-6550 5900);
WIRE 17 -1 (-5950 4850)(-6550 4850);
WIRE 16 -1 (-7400 2075)(-6675 2075);
FORCEPROP 2 LAST SIG_NAME M_L_CPU1_ALERT_N
J 0
(-7360 2085);
DISPLAY 0.489362 (-7360 2085);
WIRE 16 -1 (-6450 1125)(-5350 1125);
FORCEPROP 2 LAST SIG_NAME TP_M_L_CPU1_SA_TEST39L
J 0
(-6435 1135);
DISPLAY 0.489362 (-6435 1135);
FORCEPROP 2 LASTPROP $XRERR UNIQUE?
J 0
(-6690 1125);
DISPLAY 0.638298 (-6690 1125);
PAINT MONO (-6690 1125);
DISPLAY INVISIBLE (-6690 1125);
WIRE 16 -1 (-6475 2075)(-5350 2075);
FORCEPROP 2 LAST SIG_NAME M_L_CPU1_ALERT_R_N
J 0
(-6185 2085);
DISPLAY 0.489362 (-6185 2085);
FORCEPROP 2 LASTPROP $XRERR UNIQUE?
J 0
(-6425 2085);
DISPLAY 0.638298 (-6425 2085);
PAINT MONO (-6425 2085);
DISPLAY INVISIBLE (-6425 2085);
WIRE 16 -1 (-6450 2925)(-5350 2925);
FORCEPROP 2 LAST SIG_NAME M_L_CPU1_CLK_DP<0>
J 0
(-6450 2935);
DISPLAY 0.489362 (-6450 2935);
WIRE 16 -1 (-6450 2875)(-5350 2875);
FORCEPROP 2 LAST SIG_NAME M_L_CPU1_CLK_DN<0>
J 0
(-6450 2885);
DISPLAY 0.489362 (-6450 2885);
WIRE 16 -1 (-6450 2775)(-5350 2775);
FORCEPROP 2 LAST SIG_NAME M_L_CPU1_SA_CS_N<0>
J 0
(-6450 2785);
DISPLAY 0.489362 (-6450 2785);
WIRE 16 -1 (-6450 2725)(-5350 2725);
FORCEPROP 2 LAST SIG_NAME M_L_CPU1_SA_CS_N<1>
J 0
(-6450 2735);
DISPLAY 0.489362 (-6450 2735);
WIRE 16 -1 (-6450 2625)(-5350 2625);
FORCEPROP 2 LAST SIG_NAME M_L_CPU1_SA_RSP<0>
J 0
(-6450 2635);
DISPLAY 0.489362 (-6450 2635);
WIRE 16 -1 (-6450 2525)(-5350 2525);
FORCEPROP 2 LAST SIG_NAME M_L_CPU1_SA_PAR
J 0
(-6450 2535);
DISPLAY 0.489362 (-6450 2535);
WIRE 16 -1 (-6450 2375)(-5350 2375);
FORCEPROP 2 LAST SIG_NAME M_L_CPU1_SB_CS_N<1>
J 0
(-6450 2385);
DISPLAY 0.489362 (-6450 2385);
WIRE 16 -1 (-6450 2425)(-5350 2425);
FORCEPROP 2 LAST SIG_NAME M_L_CPU1_SB_CS_N<0>
J 0
(-6450 2435);
DISPLAY 0.489362 (-6450 2435);
WIRE 16 -1 (-6450 2175)(-5350 2175);
FORCEPROP 2 LAST SIG_NAME M_L_CPU1_SB_PAR
J 0
(-6450 2185);
DISPLAY 0.489362 (-6450 2185);
WIRE 16 -1 (-6450 2275)(-5350 2275);
FORCEPROP 2 LAST SIG_NAME M_L_CPU1_SB_RSP<0>
J 0
(-6450 2285);
DISPLAY 0.489362 (-6450 2285);
WIRE 16 -1 (-6450 1975)(-5350 1975);
FORCEPROP 2 LAST SIG_NAME M_L_CPU1_RESET_N
J 0
(-6450 1985);
DISPLAY 0.489362 (-6450 1985);
WIRE 16 -1 (-5850 3725)(-5350 3725);
WIRE 16 -1 (-5850 3375)(-5350 3375);
WIRE 16 -1 (-5850 4025)(-5350 4025);
WIRE 16 -1 (-5850 3775)(-5350 3775);
WIRE 16 -1 (-5850 3075)(-5350 3075);
WIRE 16 -1 (-5850 3475)(-5350 3475);
WIRE 16 -1 (-5850 3125)(-5350 3125);
WIRE 16 -1 (-5650 3975)(-5350 3975);
WIRE 16 -1 (-5850 3525)(-5350 3525);
WIRE 16 -1 (-5850 3175)(-5350 3175);
WIRE 16 -1 (-5650 4075)(-5350 4075);
WIRE 16 -1 (-5850 3575)(-5350 3575);
WIRE 16 -1 (-5850 3225)(-5350 3225);
WIRE 16 -1 (-5850 3625)(-5350 3625);
WIRE 16 -1 (-5850 3275)(-5350 3275);
WIRE 16 -1 (-5850 3675)(-5350 3675);
WIRE 16 -1 (-5850 3325)(-5350 3325);
WIRE 16 -1 (-5850 3925)(-5350 3925);
WIRE 16 -1 (-5650 4475)(-5350 4475);
WIRE 16 -1 (-5650 5025)(-5350 5025);
WIRE 16 -1 (-5650 4575)(-5350 4575);
WIRE 16 -1 (-5850 4125)(-5350 4125);
WIRE 16 -1 (-5650 4675)(-5350 4675);
WIRE 16 -1 (-5850 4225)(-5350 4225);
WIRE 16 -1 (-5650 4775)(-5350 4775);
WIRE 16 -1 (-5850 4325)(-5350 4325);
WIRE 16 -1 (-5650 4875)(-5350 4875);
WIRE 16 -1 (-5850 4425)(-5350 4425);
WIRE 16 -1 (-5850 4975)(-5350 4975);
WIRE 16 -1 (-5850 4525)(-5350 4525);
WIRE 16 -1 (-5850 5075)(-5350 5075);
WIRE 16 -1 (-5850 4625)(-5350 4625);
WIRE 16 -1 (-5850 4725)(-5350 4725);
WIRE 16 -1 (-5850 4825)(-5350 4825);
WIRE 16 -1 (-5650 4175)(-5350 4175);
WIRE 16 -1 (-5650 4275)(-5350 4275);
WIRE 16 -1 (-5650 4375)(-5350 4375);
WIRE 16 -1 (-5650 5125)(-5350 5125);
WIRE 16 -1 (-5650 5225)(-5350 5225);
WIRE 16 -1 (-5650 5325)(-5350 5325);
WIRE 16 -1 (-5650 5425)(-5350 5425);
WIRE 16 -1 (-5650 5525)(-5350 5525);
WIRE 16 -1 (-5650 5625)(-5350 5625);
WIRE 16 -1 (-5850 5175)(-5350 5175);
WIRE 16 -1 (-5650 5725)(-5350 5725);
WIRE 16 -1 (-5850 5275)(-5350 5275);
WIRE 16 -1 (-5650 5825)(-5350 5825);
WIRE 16 -1 (-5850 5375)(-5350 5375);
WIRE 16 -1 (-5650 5925)(-5350 5925);
WIRE 16 -1 (-5850 5475)(-5350 5475);
WIRE 16 -1 (-5850 5575)(-5350 5575);
WIRE 16 -1 (-5850 5675)(-5350 5675);
WIRE 16 -1 (-5850 5775)(-5350 5775);
WIRE 16 -1 (-5850 5875)(-5350 5875);
WIRE 16 -1 (-3750 1525)(-3325 1525);
WIRE 16 -1 (-3750 1575)(-3325 1575);
WIRE 16 -1 (-3750 1625)(-3325 1625);
WIRE 16 -1 (-3750 1675)(-3325 1675);
WIRE 16 -1 (-3750 1725)(-3325 1725);
WIRE 16 -1 (-3750 1775)(-3325 1775);
WIRE 16 -1 (-3750 1975)(-3325 1975);
WIRE 16 -1 (-3750 1825)(-3325 1825);
WIRE 16 -1 (-3750 2025)(-3325 2025);
WIRE 16 -1 (-3750 1875)(-3325 1875);
WIRE 16 -1 (-3750 2275)(-3325 2275);
WIRE 16 -1 (-3750 2325)(-3325 2325);
WIRE 16 -1 (-3750 2525)(-3325 2525);
WIRE 16 -1 (-3750 2575)(-3325 2575);
WIRE 16 -1 (-3750 2625)(-3325 2625);
WIRE 16 -1 (-3750 2675)(-3325 2675);
WIRE 16 -1 (-3750 2725)(-3325 2725);
WIRE 16 -1 (-3750 2775)(-3325 2775);
WIRE 16 -1 (-3750 2875)(-3325 2875);
WIRE 16 -1 (-3750 2925)(-3325 2925);
WIRE 16 -1 (-3750 2975)(-3325 2975);
WIRE 16 -1 (-3750 3025)(-3325 3025);
WIRE 16 -1 (-3750 2425)(-3325 2425);
WIRE 16 -1 (-3750 2075)(-3325 2075);
WIRE 16 -1 (-3750 2475)(-3325 2475);
WIRE 16 -1 (-3750 2125)(-3325 2125);
WIRE 16 -1 (-3750 2175)(-3325 2175);
WIRE 16 -1 (-3750 2225)(-3325 2225);
WIRE 16 -1 (-3750 3975)(-3325 3975);
WIRE 16 -1 (-3750 4025)(-3325 4025);
WIRE 16 -1 (-3750 4075)(-3325 4075);
WIRE 16 -1 (-3750 3075)(-3325 3075);
WIRE 16 -1 (-3750 3125)(-3325 3125);
WIRE 16 -1 (-3750 3175)(-3325 3175);
WIRE 16 -1 (-3750 3225)(-3325 3225);
WIRE 16 -1 (-3750 3325)(-3325 3325);
WIRE 16 -1 (-3750 3375)(-3325 3375);
WIRE 16 -1 (-3750 3425)(-3325 3425);
WIRE 16 -1 (-3750 3475)(-3325 3475);
WIRE 16 -1 (-3750 3525)(-3325 3525);
WIRE 16 -1 (-3750 3625)(-3325 3625);
WIRE 16 -1 (-3750 3575)(-3325 3575);
WIRE 16 -1 (-3750 3675)(-3325 3675);
WIRE 16 -1 (-3750 3775)(-3325 3775);
WIRE 16 -1 (-3750 3825)(-3325 3825);
WIRE 16 -1 (-3750 3875)(-3325 3875);
WIRE 16 -1 (-3750 3925)(-3325 3925);
WIRE 16 -1 (-3750 4775)(-3325 4775);
WIRE 16 -1 (-3750 4825)(-3325 4825);
WIRE 16 -1 (-3750 4225)(-3325 4225);
WIRE 16 -1 (-3750 4275)(-3325 4275);
WIRE 16 -1 (-3750 4125)(-3325 4125);
WIRE 16 -1 (-3750 4875)(-3325 4875);
WIRE 16 -1 (-3750 4925)(-3325 4925);
WIRE 16 -1 (-3750 4325)(-3325 4325);
WIRE 16 -1 (-3750 4975)(-3325 4975);
WIRE 16 -1 (-3750 4375)(-3325 4375);
WIRE 16 -1 (-3750 5025)(-3325 5025);
WIRE 16 -1 (-3750 4425)(-3325 4425);
WIRE 16 -1 (-3750 4475)(-3325 4475);
WIRE 16 -1 (-3750 4525)(-3325 4525);
WIRE 16 -1 (-3750 4575)(-3325 4575);
WIRE 16 -1 (-3750 4675)(-3325 4675);
WIRE 16 -1 (-3750 4725)(-3325 4725);
WIRE 16 -1 (-3750 5725)(-3325 5725);
WIRE 16 -1 (-3750 5375)(-3325 5375);
WIRE 16 -1 (-3750 5775)(-3325 5775);
WIRE 16 -1 (-3750 5825)(-3325 5825);
WIRE 16 -1 (-3750 5875)(-3325 5875);
WIRE 16 -1 (-3750 5925)(-3325 5925);
WIRE 16 -1 (-3750 5425)(-3325 5425);
WIRE 16 -1 (-3750 5125)(-3325 5125);
WIRE 16 -1 (-3750 5475)(-3325 5475);
WIRE 16 -1 (-3750 5175)(-3325 5175);
WIRE 16 -1 (-3750 5575)(-3325 5575);
WIRE 16 -1 (-3750 5225)(-3325 5225);
WIRE 16 -1 (-3750 5625)(-3325 5625);
WIRE 16 -1 (-3750 5275)(-3325 5275);
WIRE 16 -1 (-3750 5675)(-3325 5675);
WIRE 16 -1 (-3750 5325)(-3325 5325);
QUIT
